FILE_TYPE = MACRO_DRAWING;
SET COLOR_WIRE YELLOW;
SET COLOR_PROP ORANGE;
SET COLOR_DOT WHITE;
SET COLOR_ARC YELLOW;
SET COLOR_BODY GREEN;
SET COLOR_NOTE PURPLE;
SET PROP_DISPLAY VALUE;
SET PAGE_NUMBER P466;
FORCEADD UNIVERSAL_POWER..1
(-8300 5225);
FORCEPROP 3 LASTPIN (-8300 5175) SIG_NAME P12V_OCP_SFF_R\g
J 0
(-8290 5185);
DISPLAY 0.659574 (-8290 5185);
PAINT MONO (-8290 5185);
DISPLAY INVISIBLE (-8290 5185);
FORCEPROP 1 LAST HDL_POWER P12V_OCP_SFF_R
J 1
(-8300 5275);
DISPLAY 0.872340 (-8300 5275);
PAINT GREEN (-8300 5275);
FORCEPROP 2 LAST CDS_LIB pure_quanta_power
J 0
(-8300 5225);
DISPLAY INVISIBLE (-8300 5225);
FORCEPROP 1 LAST PATH I1
J 0
(-8250 5250);
DISPLAY 0.872340 (-8250 5250);
PAINT AQUA (-8250 5250);
DISPLAY INVISIBLE (-8250 5250);
FORCEADD Q_RES..1
(-5825 4875);
FORCEPROP 1 LAST LOCATION R1284
J 0
(-6075 4875);
DISPLAY 0.638298 (-6075 4875);
FORCEPROP 0 LAST $SEC 1
J 0
(-5975 4975);
DISPLAY 0.680851 (-5975 4975);
PAINT MONO (-5975 4975);
DISPLAY INVISIBLE (-5975 4975);
FORCEPROP 0 LAST CDS_SEC 1
J 0
(-5975 4975);
DISPLAY 1.021277 (-5975 4975);
DISPLAY INVISIBLE (-5975 4975);
FORCEPROP 1 LASTPIN (-5925 4875) $PN 1
J 0
(-5913 4887);
DISPLAY 0.787234 (-5913 4887);
PAINT MONO (-5913 4887);
FORCEPROP 1 LASTPIN (-5725 4875) $PN 2
J 0
(-5763 4887);
DISPLAY 0.787234 (-5763 4887);
PAINT MONO (-5763 4887);
FORCEPROP 1 LAST PACK_TYPE 0402LF
J 0
(-5700 4825);
DISPLAY 0.638298 (-5700 4825);
FORCEPROP 1 LAST WATTAGE 1/16W
J 2
(-5825 4775);
DISPLAY 0.638298 (-5825 4775);
FORCEPROP 1 LAST TOLERANCE 1%
J 0
(-5775 4825);
DISPLAY 0.638298 (-5775 4825);
FORCEPROP 1 LAST VALUE 10
J 2
(-5875 4825);
DISPLAY 0.638298 (-5875 4825);
FORCEPROP 1 LAST MATERIAL CHIP
J 0
(-5800 4775);
DISPLAY 0.638298 (-5800 4775);
FORCEPROP 2 LAST CDS_LIB pure_quanta
J 0
(-5825 4875);
DISPLAY INVISIBLE (-5825 4875);
FORCEPROP 1 LAST PATH I10
J 0
(-5875 5025);
DISPLAY 0.978723 (-5875 5025);
PAINT WHITE (-5875 5025);
DISPLAY INVISIBLE (-5875 5025);
FORCEPROP 1 LAST PART_NUMBER CS01002FB07
J 0
(-5975 4925);
DISPLAY 0.638298 (-5975 4925);
DISPLAY INVISIBLE (-5975 4925);
FORCEADD Q_RES..1
(-5825 4600);
FORCEPROP 1 LAST LOCATION R1301
J 0
(-6075 4600);
DISPLAY 0.638298 (-6075 4600);
FORCEPROP 0 LAST $SEC 1
J 0
(-5975 4700);
DISPLAY 0.680851 (-5975 4700);
PAINT MONO (-5975 4700);
DISPLAY INVISIBLE (-5975 4700);
FORCEPROP 0 LAST CDS_SEC 1
J 0
(-5975 4700);
DISPLAY 1.021277 (-5975 4700);
DISPLAY INVISIBLE (-5975 4700);
FORCEPROP 1 LASTPIN (-5925 4600) $PN 1
J 0
(-5913 4612);
DISPLAY 0.787234 (-5913 4612);
PAINT MONO (-5913 4612);
FORCEPROP 1 LASTPIN (-5725 4600) $PN 2
J 0
(-5763 4612);
DISPLAY 0.787234 (-5763 4612);
PAINT MONO (-5763 4612);
FORCEPROP 1 LAST TOLERANCE 1%
J 0
(-5775 4550);
DISPLAY 0.638298 (-5775 4550);
FORCEPROP 1 LAST PACK_TYPE 0402LF
J 0
(-5700 4550);
DISPLAY 0.638298 (-5700 4550);
FORCEPROP 1 LAST MATERIAL CHIP
J 0
(-5800 4500);
DISPLAY 0.638298 (-5800 4500);
FORCEPROP 1 LAST VALUE 10
J 2
(-5875 4550);
DISPLAY 0.638298 (-5875 4550);
FORCEPROP 1 LAST WATTAGE 1/16W
J 2
(-5825 4500);
DISPLAY 0.638298 (-5825 4500);
FORCEPROP 2 LAST CDS_LIB pure_quanta
J 0
(-5825 4600);
DISPLAY INVISIBLE (-5825 4600);
FORCEPROP 1 LAST PATH I11
J 0
(-5875 4750);
DISPLAY 0.978723 (-5875 4750);
PAINT WHITE (-5875 4750);
DISPLAY INVISIBLE (-5875 4750);
FORCEPROP 1 LAST PART_NUMBER CS01002FB07
J 0
(-5975 4650);
DISPLAY 0.638298 (-5975 4650);
DISPLAY INVISIBLE (-5975 4650);
FORCEADD Q_RES..1
(-6650 5775);
FORCEPROP 1 LAST LOCATION R1306
J 0
(-6775 5775);
DISPLAY 0.638298 (-6775 5775);
FORCEPROP 0 LAST $SEC 1
J 0
(-6775 5825);
DISPLAY 0.680851 (-6775 5825);
PAINT MONO (-6775 5825);
DISPLAY INVISIBLE (-6775 5825);
FORCEPROP 0 LAST CDS_SEC 1
J 0
(-6775 5825);
DISPLAY 1.021277 (-6775 5825);
DISPLAY INVISIBLE (-6775 5825);
FORCEPROP 1 LASTPIN (-6750 5775) $PN 1
J 0
(-6738 5787);
DISPLAY 0.787234 (-6738 5787);
PAINT MONO (-6738 5787);
FORCEPROP 1 LASTPIN (-6550 5775) $PN 2
J 0
(-6588 5787);
DISPLAY 0.787234 (-6588 5787);
PAINT MONO (-6588 5787);
FORCEPROP 1 LAST PACK_TYPE 0402LF
J 0
(-6175 5775);
DISPLAY 0.510638 (-6175 5775);
FORCEPROP 1 LAST TOLERANCE 1%
J 0
(-6325 5775);
DISPLAY 0.510638 (-6325 5775);
FORCEPROP 1 LAST WATTAGE 1/16W
J 2
(-6325 5775);
DISPLAY 0.510638 (-6325 5775);
FORCEPROP 1 LAST MATERIAL EMPTY
J 0
(-6275 5775);
DISPLAY 0.510638 (-6275 5775);
PAINT RED (-6275 5775);
FORCEPROP 1 LAST VALUE 4.7K
J 2
(-6450 5775);
DISPLAY 0.510638 (-6450 5775);
FORCEPROP 2 LAST CDS_LIB pure_quanta
J 0
(-6650 5775);
DISPLAY INVISIBLE (-6650 5775);
FORCEPROP 1 LAST PATH I12
J 0
(-6700 5925);
DISPLAY 0.978723 (-6700 5925);
PAINT WHITE (-6700 5925);
DISPLAY INVISIBLE (-6700 5925);
FORCEPROP 1 LAST PART_NUMBER CS24702FB06
J 0
(-7075 5775);
DISPLAY 0.510638 (-7075 5775);
DISPLAY INVISIBLE (-7075 5775);
FORCEADD Q_RES..1
(-6650 5725);
FORCEPROP 1 LAST LOCATION R1309
J 0
(-6775 5725);
DISPLAY 0.638298 (-6775 5725);
FORCEPROP 0 LAST $SEC 1
J 0
(-6775 5775);
DISPLAY 0.680851 (-6775 5775);
PAINT MONO (-6775 5775);
DISPLAY INVISIBLE (-6775 5775);
FORCEPROP 0 LAST CDS_SEC 1
J 0
(-6775 5775);
DISPLAY 1.021277 (-6775 5775);
DISPLAY INVISIBLE (-6775 5775);
FORCEPROP 1 LASTPIN (-6750 5725) $PN 1
J 0
(-6738 5737);
DISPLAY 0.787234 (-6738 5737);
PAINT MONO (-6738 5737);
FORCEPROP 1 LASTPIN (-6550 5725) $PN 2
J 0
(-6588 5737);
DISPLAY 0.787234 (-6588 5737);
PAINT MONO (-6588 5737);
FORCEPROP 1 LAST WATTAGE 1/16W
J 2
(-6325 5725);
DISPLAY 0.510638 (-6325 5725);
FORCEPROP 1 LAST VALUE 4.7K
J 2
(-6450 5725);
DISPLAY 0.510638 (-6450 5725);
FORCEPROP 1 LAST PACK_TYPE 0402LF
J 0
(-6175 5725);
DISPLAY 0.510638 (-6175 5725);
FORCEPROP 1 LAST MATERIAL EMPTY
J 0
(-6275 5725);
DISPLAY 0.510638 (-6275 5725);
PAINT RED (-6275 5725);
FORCEPROP 1 LAST TOLERANCE 1%
J 0
(-6325 5725);
DISPLAY 0.510638 (-6325 5725);
FORCEPROP 2 LAST CDS_LIB pure_quanta
J 0
(-6650 5725);
DISPLAY INVISIBLE (-6650 5725);
FORCEPROP 1 LAST PATH I13
J 0
(-6700 5875);
DISPLAY 0.978723 (-6700 5875);
PAINT WHITE (-6700 5875);
DISPLAY INVISIBLE (-6700 5875);
FORCEPROP 1 LAST PART_NUMBER CS24702FB06
J 0
(-7075 5725);
DISPLAY 0.510638 (-7075 5725);
DISPLAY INVISIBLE (-7075 5725);
FORCEADD Q_RES..1
(-5850 5425);
FORCEPROP 1 LAST LOCATION R1276
J 0
(-6125 5425);
DISPLAY 0.787234 (-6125 5425);
FORCEPROP 0 LAST $SEC 1
J 0
(-5550 5475);
DISPLAY 0.680851 (-5550 5475);
PAINT MONO (-5550 5475);
DISPLAY INVISIBLE (-5550 5475);
FORCEPROP 0 LAST CDS_SEC 1
J 0
(-5550 5475);
DISPLAY 0.680851 (-5550 5475);
DISPLAY INVISIBLE (-5550 5475);
FORCEPROP 1 LASTPIN (-5950 5425) $PN 1
J 0
(-5938 5437);
DISPLAY 0.787234 (-5938 5437);
PAINT MONO (-5938 5437);
FORCEPROP 1 LASTPIN (-5750 5425) $PN 2
J 0
(-5788 5437);
DISPLAY 0.787234 (-5788 5437);
PAINT MONO (-5788 5437);
FORCEPROP 1 LAST MATERIAL CHIP
J 0
(-5625 5425);
DISPLAY 0.510638 (-5625 5425);
FORCEPROP 1 LAST VALUE 0
J 2
(-5700 5425);
DISPLAY 0.510638 (-5700 5425);
FORCEPROP 1 LAST TOLERANCE 5%
J 0
(-5675 5425);
DISPLAY 0.510638 (-5675 5425);
FORCEPROP 1 LAST PACK_TYPE 0402LF
J 0
(-5950 5500);
DISPLAY 0.404255 (-5950 5500);
DISPLAY INVISIBLE (-5950 5500);
FORCEPROP 1 LAST WATTAGE 1/16W
J 2
(-5675 5500);
DISPLAY 0.510638 (-5675 5500);
DISPLAY INVISIBLE (-5675 5500);
FORCEPROP 2 LAST CDS_LIB pure_quanta
J 0
(-5850 5425);
DISPLAY INVISIBLE (-5850 5425);
FORCEPROP 1 LAST PATH I14
J 0
(-5900 5575);
DISPLAY 0.978723 (-5900 5575);
PAINT WHITE (-5900 5575);
DISPLAY INVISIBLE (-5900 5575);
FORCEPROP 1 LAST PART_NUMBER CS00002JB13
J 0
(-5950 5475);
DISPLAY 0.404255 (-5950 5475);
DISPLAY INVISIBLE (-5950 5475);
FORCEADD Q_CAP..1
(-5475 4725);
FORCEPROP 1 LAST LOCATION C1111
J 0
(-5425 4825);
DISPLAY 0.978723 (-5425 4825);
FORCEPROP 0 LAST $SEC 1
J 0
(-5425 4875);
DISPLAY 0.680851 (-5425 4875);
PAINT MONO (-5425 4875);
DISPLAY INVISIBLE (-5425 4875);
FORCEPROP 0 LAST CDS_SEC 1
J 0
(-5425 4875);
DISPLAY 1.021277 (-5425 4875);
DISPLAY INVISIBLE (-5425 4875);
FORCEPROP 1 LASTPIN (-5475 4825) $PN 1
J 0
(-5465 4805);
DISPLAY 0.787234 (-5465 4805);
PAINT MONO (-5465 4805);
FORCEPROP 1 LASTPIN (-5475 4625) $PN 2
J 0
(-5465 4605);
DISPLAY 0.787234 (-5465 4605);
PAINT MONO (-5465 4605);
FORCEPROP 1 LAST VOLTAGE 25V
J 0
(-5425 4750);
DISPLAY 0.510638 (-5425 4750);
FORCEPROP 1 LAST TOLERANCE 10%
J 0
(-5425 4725);
DISPLAY 0.510638 (-5425 4725);
FORCEPROP 1 LAST MATERIAL X7R
J 0
(-5425 4700);
DISPLAY 0.510638 (-5425 4700);
FORCEPROP 1 LAST PACK_TYPE 0402
J 0
(-5425 4650);
DISPLAY 0.510638 (-5425 4650);
FORCEPROP 1 LAST VALUE 0.1UF
J 0
(-5425 4775);
DISPLAY 0.510638 (-5425 4775);
FORCEPROP 2 LAST CDS_LIB pure_quanta
J 0
(-5475 4725);
DISPLAY INVISIBLE (-5475 4725);
FORCEPROP 1 LAST PATH I15
J 0
(-5425 4875);
DISPLAY 0.978723 (-5425 4875);
PAINT WHITE (-5425 4875);
DISPLAY INVISIBLE (-5425 4875);
FORCEPROP 1 LAST PART_NUMBER CH4104K1B00
J 0
(-5425 4675);
DISPLAY 0.510638 (-5425 4675);
DISPLAY INVISIBLE (-5425 4675);
FORCEADD Q_RES..2
(-5550 6075);
FORCEPROP 1 LAST LOCATION R1320
J 0
(-5505 6200);
DISPLAY 0.978723 (-5505 6200);
FORCEPROP 0 LAST $SEC 1
J 0
(-5500 6250);
DISPLAY 0.680851 (-5500 6250);
PAINT MONO (-5500 6250);
DISPLAY INVISIBLE (-5500 6250);
FORCEPROP 0 LAST CDS_SEC 1
J 0
(-5500 6250);
DISPLAY 1.021277 (-5500 6250);
DISPLAY INVISIBLE (-5500 6250);
FORCEPROP 1 LASTPIN (-5550 6175) $PN 1
J 0
(-5545 6137);
DISPLAY 0.787234 (-5545 6137);
PAINT MONO (-5545 6137);
FORCEPROP 1 LASTPIN (-5550 5975) $PN 2
J 0
(-5545 5985);
DISPLAY 0.787234 (-5545 5985);
PAINT MONO (-5545 5985);
FORCEPROP 1 LAST MATERIAL CHIP
J 0
(-5510 6000);
DISPLAY 0.510638 (-5510 6000);
FORCEPROP 1 LAST WATTAGE 1/16W
J 0
(-5510 6050);
DISPLAY 0.510638 (-5510 6050);
FORCEPROP 1 LAST TOLERANCE 1%
J 0
(-5505 6100);
DISPLAY 0.510638 (-5505 6100);
FORCEPROP 1 LAST PACK_TYPE 0402LF
J 0
(-5510 5900);
DISPLAY 0.510638 (-5510 5900);
FORCEPROP 1 LAST VALUE 4.7K
J 0
(-5505 6150);
DISPLAY 0.510638 (-5505 6150);
FORCEPROP 2 LAST CDS_LIB pure_quanta
J 0
(-5550 6075);
DISPLAY INVISIBLE (-5550 6075);
FORCEPROP 1 LAST PATH I17
J 0
(-5500 6250);
DISPLAY 0.978723 (-5500 6250);
PAINT WHITE (-5500 6250);
DISPLAY INVISIBLE (-5500 6250);
FORCEPROP 1 LAST PART_NUMBER CS24702FB06
J 0
(-5510 5950);
DISPLAY 0.510638 (-5510 5950);
DISPLAY INVISIBLE (-5510 5950);
FORCEADD UNIVERSAL_GND..1
(-4950 5850);
FORCEPROP 3 LASTPIN (-4950 5900) SIG_NAME GND\g
J 0
(-4940 5910);
DISPLAY 0.659574 (-4940 5910);
PAINT MONO (-4940 5910);
DISPLAY INVISIBLE (-4940 5910);
FORCEPROP 2 LAST CDS_LIB pure_quanta_power
J 0
(-4950 5850);
DISPLAY INVISIBLE (-4950 5850);
FORCEPROP 1 LAST HDL_POWER GND
J 1
(-4925 5775);
DISPLAY 0.872340 (-4925 5775);
PAINT GREEN (-4925 5775);
DISPLAY INVISIBLE (-4925 5775);
FORCEPROP 1 LAST PATH I18
J 0
(-4875 5850);
DISPLAY 0.872340 (-4875 5850);
PAINT AQUA (-4875 5850);
DISPLAY INVISIBLE (-4875 5850);
FORCEADD Q_CAP..1
(-4950 6075);
FORCEPROP 1 LAST LOCATION C1097
J 0
(-4900 6175);
DISPLAY 0.978723 (-4900 6175);
FORCEPROP 0 LAST $SEC 1
J 0
(-4900 6225);
DISPLAY 0.680851 (-4900 6225);
PAINT MONO (-4900 6225);
DISPLAY INVISIBLE (-4900 6225);
FORCEPROP 0 LAST CDS_SEC 1
J 0
(-4900 6225);
DISPLAY 1.021277 (-4900 6225);
DISPLAY INVISIBLE (-4900 6225);
FORCEPROP 1 LASTPIN (-4950 6175) $PN 1
J 0
(-4940 6155);
DISPLAY 0.787234 (-4940 6155);
PAINT MONO (-4940 6155);
FORCEPROP 1 LASTPIN (-4950 5975) $PN 2
J 0
(-4940 5955);
DISPLAY 0.787234 (-4940 5955);
PAINT MONO (-4940 5955);
FORCEPROP 1 LAST MATERIAL X7R
J 0
(-4900 5975);
DISPLAY 0.638298 (-4900 5975);
FORCEPROP 1 LAST PACK_TYPE 0402
J 0
(-4900 5925);
DISPLAY 0.638298 (-4900 5925);
FORCEPROP 1 LAST VOLTAGE 25V
J 0
(-4900 6075);
DISPLAY 0.638298 (-4900 6075);
FORCEPROP 1 LAST VALUE 0.1UF
J 0
(-4900 6125);
DISPLAY 0.638298 (-4900 6125);
FORCEPROP 1 LAST TOLERANCE 10%
J 0
(-4900 6025);
DISPLAY 0.638298 (-4900 6025);
FORCEPROP 2 LAST CDS_LIB pure_quanta
J 0
(-4950 6075);
DISPLAY INVISIBLE (-4950 6075);
FORCEPROP 1 LAST PATH I19
J 0
(-4900 6225);
DISPLAY 0.978723 (-4900 6225);
PAINT WHITE (-4900 6225);
DISPLAY INVISIBLE (-4900 6225);
FORCEPROP 1 LAST PART_NUMBER CH4104K1B00
J 0
(-4900 5925);
DISPLAY 0.808511 (-4900 5925);
DISPLAY INVISIBLE (-4900 5925);
FORCEADD Q_RES..1
(-7725 5075);
FORCEPROP 1 LAST LOCATION R1324
J 0
(-7775 5125);
DISPLAY 0.978723 (-7775 5125);
FORCEPROP 0 LAST $SEC 1
J 0
(-7775 5175);
DISPLAY 0.680851 (-7775 5175);
PAINT MONO (-7775 5175);
DISPLAY INVISIBLE (-7775 5175);
FORCEPROP 0 LAST CDS_SEC 1
J 0
(-7775 5175);
DISPLAY 1.021277 (-7775 5175);
DISPLAY INVISIBLE (-7775 5175);
FORCEPROP 1 LASTPIN (-7825 5075) $PN 1
J 0
(-7813 5087);
DISPLAY 0.787234 (-7813 5087);
PAINT MONO (-7813 5087);
FORCEPROP 1 LASTPIN (-7625 5075) $PN 2
J 0
(-7663 5087);
DISPLAY 0.787234 (-7663 5087);
PAINT MONO (-7663 5087);
FORCEPROP 1 LAST TOLERANCE 1%
J 0
(-7725 4975);
DISPLAY 0.510638 (-7725 4975);
FORCEPROP 1 LAST WATTAGE 2W
J 2
(-7750 4925);
DISPLAY 0.510638 (-7750 4925);
FORCEPROP 1 LAST MATERIAL CHIP
J 0
(-7725 4925);
DISPLAY 0.510638 (-7725 4925);
FORCEPROP 1 LAST PACK_TYPE 2512LF
J 0
(-7650 4975);
DISPLAY 0.510638 (-7650 4975);
FORCEPROP 1 LAST VALUE 0.002
J 2
(-7750 4975);
DISPLAY 0.510638 (-7750 4975);
FORCEPROP 2 LAST CDS_LIB pure_quanta
J 0
(-7725 5075);
DISPLAY INVISIBLE (-7725 5075);
FORCEPROP 1 LAST PATH I2
J 0
(-7775 5225);
DISPLAY 0.978723 (-7775 5225);
PAINT WHITE (-7775 5225);
DISPLAY INVISIBLE (-7775 5225);
FORCEPROP 1 LAST PART_NUMBER CS+002AFR06
J 0
(-7850 5025);
DISPLAY 0.510638 (-7850 5025);
DISPLAY INVISIBLE (-7850 5025);
FORCEADD UNIVERSAL_POWER..1
(-5550 6375);
FORCEPROP 3 LASTPIN (-5550 6325) SIG_NAME P3V3_AUX\g
J 0
(-5540 6335);
DISPLAY 0.659574 (-5540 6335);
PAINT MONO (-5540 6335);
DISPLAY INVISIBLE (-5540 6335);
FORCEPROP 1 LAST HDL_POWER P3V3_AUX
J 1
(-5550 6425);
DISPLAY 0.872340 (-5550 6425);
PAINT GREEN (-5550 6425);
FORCEPROP 2 LAST CDS_LIB pure_quanta_power
J 0
(-5550 6375);
DISPLAY INVISIBLE (-5550 6375);
FORCEPROP 1 LAST PATH I20
J 0
(-5500 6400);
DISPLAY 0.872340 (-5500 6400);
PAINT AQUA (-5500 6400);
DISPLAY INVISIBLE (-5500 6400);
FORCEADD UNIVERSAL_POWER..1
(-4700 6475);
FORCEPROP 3 LASTPIN (-4700 6425) SIG_NAME P3V3_AUX\g
J 0
(-4690 6435);
DISPLAY 0.659574 (-4690 6435);
PAINT MONO (-4690 6435);
DISPLAY INVISIBLE (-4690 6435);
FORCEPROP 1 LAST HDL_POWER P3V3_AUX
J 1
(-4700 6525);
DISPLAY 0.872340 (-4700 6525);
PAINT GREEN (-4700 6525);
FORCEPROP 2 LAST CDS_LIB pure_quanta_power
J 0
(-4700 6475);
DISPLAY INVISIBLE (-4700 6475);
FORCEPROP 1 LAST PATH I21
J 0
(-4650 6500);
DISPLAY 0.872340 (-4650 6500);
PAINT AQUA (-4650 6500);
DISPLAY INVISIBLE (-4650 6500);
FORCEADD UNIVERSAL_GND..1
(-3625 4825);
FORCEPROP 3 LASTPIN (-3625 4875) SIG_NAME GND\g
J 0
(-3615 4885);
DISPLAY 0.659574 (-3615 4885);
PAINT MONO (-3615 4885);
DISPLAY INVISIBLE (-3615 4885);
FORCEPROP 2 LAST CDS_LIB pure_quanta_power
J 0
(-3625 4825);
DISPLAY INVISIBLE (-3625 4825);
FORCEPROP 1 LAST HDL_POWER GND
J 1
(-3600 4750);
DISPLAY 0.872340 (-3600 4750);
PAINT GREEN (-3600 4750);
DISPLAY INVISIBLE (-3600 4750);
FORCEPROP 1 LAST PATH I22
J 0
(-3550 4825);
DISPLAY 0.872340 (-3550 4825);
PAINT AQUA (-3550 4825);
DISPLAY INVISIBLE (-3550 4825);
FORCEADD Q_RES..1
(-2525 5725);
FORCEPROP 1 LAST LOCATION R1270
J 0
(-2700 5725);
DISPLAY 0.510638 (-2700 5725);
FORCEPROP 0 LAST $SEC 1
J 0
(-2225 5775);
DISPLAY 0.680851 (-2225 5775);
PAINT MONO (-2225 5775);
DISPLAY INVISIBLE (-2225 5775);
FORCEPROP 0 LAST CDS_SEC 1
J 0
(-2225 5775);
DISPLAY 1.021277 (-2225 5775);
DISPLAY INVISIBLE (-2225 5775);
FORCEPROP 1 LASTPIN (-2625 5725) $PN 1
J 0
(-2613 5737);
DISPLAY 0.787234 (-2613 5737);
PAINT MONO (-2613 5737);
FORCEPROP 1 LASTPIN (-2425 5725) $PN 2
J 0
(-2463 5737);
DISPLAY 0.787234 (-2463 5737);
PAINT MONO (-2463 5737);
FORCEPROP 1 LAST VALUE 0
J 2
(-2375 5725);
DISPLAY 0.574468 (-2375 5725);
FORCEPROP 1 LAST MATERIAL CHIP
J 0
(-2350 5725);
DISPLAY 0.574468 (-2350 5725);
FORCEPROP 1 LAST PACK_TYPE 0402LF
J 0
(-2225 5725);
DISPLAY 0.574468 (-2225 5725);
FORCEPROP 1 LAST WATTAGE 1/16W
J 2
(-2450 5650);
DISPLAY 0.723404 (-2450 5650);
PAINT SKYBLUE (-2450 5650);
DISPLAY INVISIBLE (-2450 5650);
FORCEPROP 1 LAST TOLERANCE 5%
J 0
(-2725 5650);
DISPLAY 0.723404 (-2725 5650);
PAINT SKYBLUE (-2725 5650);
DISPLAY INVISIBLE (-2725 5650);
FORCEPROP 2 LAST CDS_LIB pure_quanta
J 0
(-2525 5725);
DISPLAY INVISIBLE (-2525 5725);
FORCEPROP 1 LAST PATH I23
J 0
(-2575 5875);
DISPLAY 0.978723 (-2575 5875);
PAINT WHITE (-2575 5875);
DISPLAY INVISIBLE (-2575 5875);
FORCEPROP 1 LAST PART_NUMBER CS00002JB13
J 0
(-2800 5600);
DISPLAY 0.723404 (-2800 5600);
PAINT WHITE (-2800 5600);
DISPLAY INVISIBLE (-2800 5600);
FORCEADD OFFPAGE..2
(-975 5725);
FORCEPROP 2 LAST $XR1 82 
J 0
(-666 5725);
DISPLAY 0.638298 (-666 5725);
PAINT MONO (-666 5725);
FORCEPROP 2 LAST $XR0 237 
J 0
(-786 5725);
DISPLAY 0.638298 (-786 5725);
PAINT MONO (-786 5725);
FORCEPROP 2 LAST CDS_LIB standard
J 0
(-975 5725);
DISPLAY INVISIBLE (-975 5725);
FORCEPROP 1 LAST OFFPAGE TRUE
J 0
(-650 5600);
DISPLAY 0.872340 (-650 5600);
DISPLAY INVISIBLE (-650 5600);
FORCEPROP 1 LAST COMMENT_BODY TRUE
J 0
(-1020 5630);
DISPLAY 0.872340 (-1020 5630);
PAINT GREEN (-1020 5630);
DISPLAY INVISIBLE (-1020 5630);
FORCEPROP 2 LAST PATH I25
J 0
(-775 5775);
DISPLAY 0.680851 (-775 5775);
DISPLAY INVISIBLE (-775 5775);
FORCEADD Q_RES..1
(-5850 5475);
FORCEPROP 1 LAST LOCATION R1273
J 0
(-6125 5475);
DISPLAY 0.787234 (-6125 5475);
FORCEPROP 0 LAST $SEC 1
J 0
(-5675 5575);
DISPLAY 0.680851 (-5675 5575);
PAINT MONO (-5675 5575);
DISPLAY INVISIBLE (-5675 5575);
FORCEPROP 0 LAST CDS_SEC 1
J 0
(-5675 5575);
DISPLAY 0.680851 (-5675 5575);
DISPLAY INVISIBLE (-5675 5575);
FORCEPROP 1 LASTPIN (-5950 5475) $PN 1
J 0
(-5938 5487);
DISPLAY 0.787234 (-5938 5487);
PAINT MONO (-5938 5487);
FORCEPROP 1 LASTPIN (-5750 5475) $PN 2
J 0
(-5788 5487);
DISPLAY 0.787234 (-5788 5487);
PAINT MONO (-5788 5487);
FORCEPROP 1 LAST WATTAGE 1/16W
J 2
(-5675 5550);
DISPLAY 0.510638 (-5675 5550);
FORCEPROP 1 LAST VALUE 0
J 2
(-5700 5475);
DISPLAY 0.510638 (-5700 5475);
FORCEPROP 1 LAST MATERIAL CHIP
J 0
(-5625 5475);
DISPLAY 0.510638 (-5625 5475);
FORCEPROP 1 LAST TOLERANCE 5%
J 0
(-5675 5475);
DISPLAY 0.510638 (-5675 5475);
FORCEPROP 1 LAST PACK_TYPE 0402LF
J 0
(-5950 5550);
DISPLAY 0.404255 (-5950 5550);
FORCEPROP 2 LAST CDS_LIB pure_quanta
J 0
(-5850 5475);
DISPLAY INVISIBLE (-5850 5475);
FORCEPROP 1 LAST PATH I27
J 0
(-5900 5625);
DISPLAY 0.978723 (-5900 5625);
PAINT WHITE (-5900 5625);
DISPLAY INVISIBLE (-5900 5625);
FORCEPROP 1 LAST PART_NUMBER CS00002JB13
J 0
(-5950 5525);
DISPLAY 0.404255 (-5950 5525);
DISPLAY INVISIBLE (-5950 5525);
FORCEADD ISL28022FRZT..1
(-4200 5475);
FORCEPROP 1 LAST LOCATION U55
J 0
(-4495 6056);
DISPLAY 0.723404 (-4495 6056);
PAINT GREEN (-4495 6056);
FORCEPROP 2 LAST SEC 1
J 0
(-4475 6200);
DISPLAY 0.680851 (-4475 6200);
PAINT MONO (-4475 6200);
DISPLAY INVISIBLE (-4475 6200);
FORCEPROP 2 LASTPIN (-4650 5575) $PN 2
J 2
(-4660 5585);
DISPLAY 0.680851 (-4660 5585);
PAINT MONO (-4660 5585);
FORCEPROP 2 LASTPIN (-4650 5625) $PN 1
J 2
(-4660 5635);
DISPLAY 0.680851 (-4660 5635);
PAINT MONO (-4660 5635);
FORCEPROP 2 LASTPIN (-3750 5725) $PN 3
J 0
(-3740 5735);
DISPLAY 0.680851 (-3740 5735);
PAINT MONO (-3740 5735);
FORCEPROP 2 LASTPIN (-3750 5275) $PN 10
J 0
(-3740 5285);
DISPLAY 0.680851 (-3740 5285);
PAINT MONO (-3740 5285);
FORCEPROP 2 LASTPIN (-3750 5625) $PN 6
J 0
(-3740 5635);
DISPLAY 0.680851 (-3740 5635);
PAINT MONO (-3740 5635);
FORCEPROP 2 LASTPIN (-3750 5575) $PN 7
J 0
(-3740 5585);
DISPLAY 0.680851 (-3740 5585);
PAINT MONO (-3740 5585);
FORCEPROP 2 LASTPIN (-3750 5525) $PN 8
J 0
(-3740 5535);
DISPLAY 0.680851 (-3740 5535);
PAINT MONO (-3740 5535);
FORCEPROP 2 LASTPIN (-3750 5475) $PN 14
J 0
(-3740 5485);
DISPLAY 0.680851 (-3740 5485);
PAINT MONO (-3740 5485);
FORCEPROP 2 LASTPIN (-3750 5425) $PN 15
J 0
(-3740 5435);
DISPLAY 0.680851 (-3740 5435);
PAINT MONO (-3740 5435);
FORCEPROP 2 LASTPIN (-3750 5375) $PN 16
J 0
(-3740 5385);
DISPLAY 0.680851 (-3740 5385);
PAINT MONO (-3740 5385);
FORCEPROP 2 LASTPIN (-4650 5475) $PN 5
J 2
(-4660 5485);
DISPLAY 0.680851 (-4660 5485);
PAINT MONO (-4660 5485);
FORCEPROP 2 LASTPIN (-4650 5425) $PN 4
J 2
(-4660 5435);
DISPLAY 0.680851 (-4660 5435);
PAINT MONO (-4660 5435);
FORCEPROP 2 LASTPIN (-3750 5225) $PN TH
J 0
(-3740 5235);
DISPLAY 0.680851 (-3740 5235);
PAINT MONO (-3740 5235);
FORCEPROP 2 LASTPIN (-4650 5325) $PN 11
J 2
(-4660 5335);
DISPLAY 0.680851 (-4660 5335);
PAINT MONO (-4660 5335);
FORCEPROP 2 LASTPIN (-4650 5725) $PN 9
J 2
(-4660 5735);
DISPLAY 0.680851 (-4660 5735);
PAINT MONO (-4660 5735);
FORCEPROP 2 LASTPIN (-4650 5225) $PN 12
J 2
(-4660 5235);
DISPLAY 0.680851 (-4660 5235);
PAINT MONO (-4660 5235);
FORCEPROP 2 LASTPIN (-4650 5275) $PN 13
J 2
(-4660 5285);
DISPLAY 0.680851 (-4660 5285);
PAINT MONO (-4660 5285);
FORCEPROP 2 LAST PART_TYPE SMLF
J 0
(-4475 6150);
DISPLAY 1.021277 (-4475 6150);
FORCEPROP 2 LAST VALUE ISL28022FRZ-T
J 0
(-4475 6100);
DISPLAY 1.021277 (-4475 6100);
FORCEPROP 1 LAST MATERIAL IC
J 0
(-4495 5782);
DISPLAY 0.723404 (-4495 5782);
PAINT GREEN (-4495 5782);
FORCEPROP 2 LAST SEC_TYPE 
J 0
(-4475 6200);
DISPLAY 1.021277 (-4475 6200);
DISPLAY INVISIBLE (-4475 6200);
FORCEPROP 1 LAST CDS_LMAN_SYM_OUTLINE -300,300,300,-300
J 0
(-4200 5475);
DISPLAY 0.468085 (-4200 5475);
PAINT GREEN (-4200 5475);
DISPLAY INVISIBLE (-4200 5475);
FORCEPROP 1 LAST NEEDS_NO_SIZE TRUE
J 0
(-4200 5475);
DISPLAY 0.723404 (-4200 5475);
PAINT GREEN (-4200 5475);
DISPLAY INVISIBLE (-4200 5475);
FORCEPROP 2 LAST CDS_LIB pure_quanta
J 0
(-4200 5475);
DISPLAY INVISIBLE (-4200 5475);
FORCEPROP 1 LAST PATH I28
J 0
(-4200 5475);
DISPLAY 0.723404 (-4200 5475);
PAINT GREEN (-4200 5475);
DISPLAY INVISIBLE (-4200 5475);
FORCEPROP 1 LAST PART_NUMBER AL028022003
J 0
(-4495 5909);
DISPLAY 0.723404 (-4495 5909);
PAINT GREEN (-4495 5909);
DISPLAY INVISIBLE (-4495 5909);
FORCEADD ISL28022FRZT..1
(-3550 3425);
FORCEPROP 1 LAST LOCATION U56
J 0
(-3845 4006);
DISPLAY 0.723404 (-3845 4006);
PAINT GREEN (-3845 4006);
FORCEPROP 2 LAST SEC 1
J 0
(-3825 4150);
DISPLAY 0.680851 (-3825 4150);
PAINT MONO (-3825 4150);
DISPLAY INVISIBLE (-3825 4150);
FORCEPROP 2 LASTPIN (-4000 3525) $PN 2
J 2
(-4010 3535);
DISPLAY 0.680851 (-4010 3535);
PAINT MONO (-4010 3535);
FORCEPROP 2 LASTPIN (-4000 3575) $PN 1
J 2
(-4010 3585);
DISPLAY 0.680851 (-4010 3585);
PAINT MONO (-4010 3585);
FORCEPROP 2 LASTPIN (-3100 3675) $PN 3
J 0
(-3090 3685);
DISPLAY 0.680851 (-3090 3685);
PAINT MONO (-3090 3685);
FORCEPROP 2 LASTPIN (-3100 3225) $PN 10
J 0
(-3090 3235);
DISPLAY 0.680851 (-3090 3235);
PAINT MONO (-3090 3235);
FORCEPROP 2 LASTPIN (-3100 3575) $PN 6
J 0
(-3090 3585);
DISPLAY 0.680851 (-3090 3585);
PAINT MONO (-3090 3585);
FORCEPROP 2 LASTPIN (-3100 3525) $PN 7
J 0
(-3090 3535);
DISPLAY 0.680851 (-3090 3535);
PAINT MONO (-3090 3535);
FORCEPROP 2 LASTPIN (-3100 3475) $PN 8
J 0
(-3090 3485);
DISPLAY 0.680851 (-3090 3485);
PAINT MONO (-3090 3485);
FORCEPROP 2 LASTPIN (-3100 3425) $PN 14
J 0
(-3090 3435);
DISPLAY 0.680851 (-3090 3435);
PAINT MONO (-3090 3435);
FORCEPROP 2 LASTPIN (-3100 3375) $PN 15
J 0
(-3090 3385);
DISPLAY 0.680851 (-3090 3385);
PAINT MONO (-3090 3385);
FORCEPROP 2 LASTPIN (-3100 3325) $PN 16
J 0
(-3090 3335);
DISPLAY 0.680851 (-3090 3335);
PAINT MONO (-3090 3335);
FORCEPROP 2 LASTPIN (-4000 3425) $PN 5
J 2
(-4010 3435);
DISPLAY 0.680851 (-4010 3435);
PAINT MONO (-4010 3435);
FORCEPROP 2 LASTPIN (-4000 3375) $PN 4
J 2
(-4010 3385);
DISPLAY 0.680851 (-4010 3385);
PAINT MONO (-4010 3385);
FORCEPROP 2 LASTPIN (-3100 3175) $PN TH
J 0
(-3090 3185);
DISPLAY 0.680851 (-3090 3185);
PAINT MONO (-3090 3185);
FORCEPROP 2 LASTPIN (-4000 3275) $PN 11
J 2
(-4010 3285);
DISPLAY 0.680851 (-4010 3285);
PAINT MONO (-4010 3285);
FORCEPROP 2 LASTPIN (-4000 3675) $PN 9
J 2
(-4010 3685);
DISPLAY 0.680851 (-4010 3685);
PAINT MONO (-4010 3685);
FORCEPROP 2 LASTPIN (-4000 3175) $PN 12
J 2
(-4010 3185);
DISPLAY 0.680851 (-4010 3185);
PAINT MONO (-4010 3185);
FORCEPROP 2 LASTPIN (-4000 3225) $PN 13
J 2
(-4010 3235);
DISPLAY 0.680851 (-4010 3235);
PAINT MONO (-4010 3235);
FORCEPROP 2 LAST PART_TYPE SMLF
J 0
(-3825 4100);
DISPLAY 1.021277 (-3825 4100);
FORCEPROP 2 LAST VALUE ISL28022FRZ-T
J 0
(-3825 4050);
DISPLAY 1.021277 (-3825 4050);
FORCEPROP 1 LAST MATERIAL IC
J 0
(-3845 3732);
DISPLAY 0.723404 (-3845 3732);
PAINT GREEN (-3845 3732);
FORCEPROP 2 LAST CDS_LIB pure_quanta
J 0
(-3550 3425);
DISPLAY INVISIBLE (-3550 3425);
FORCEPROP 1 LAST NEEDS_NO_SIZE TRUE
J 0
(-3550 3425);
DISPLAY 0.723404 (-3550 3425);
PAINT GREEN (-3550 3425);
DISPLAY INVISIBLE (-3550 3425);
FORCEPROP 1 LAST CDS_LMAN_SYM_OUTLINE -300,300,300,-300
J 0
(-3550 3425);
DISPLAY 0.468085 (-3550 3425);
PAINT GREEN (-3550 3425);
DISPLAY INVISIBLE (-3550 3425);
FORCEPROP 2 LAST SEC_TYPE 
J 0
(-3825 4150);
DISPLAY 1.021277 (-3825 4150);
DISPLAY INVISIBLE (-3825 4150);
FORCEPROP 1 LAST PATH I29
J 0
(-3550 3425);
DISPLAY 0.723404 (-3550 3425);
PAINT GREEN (-3550 3425);
DISPLAY INVISIBLE (-3550 3425);
FORCEPROP 1 LAST PART_NUMBER AL028022003
J 0
(-3845 3859);
DISPLAY 0.723404 (-3845 3859);
PAINT GREEN (-3845 3859);
DISPLAY INVISIBLE (-3845 3859);
FORCEADD UNIVERSAL_POWER..1
(-7225 5225);
FORCEPROP 3 LASTPIN (-7225 5175) SIG_NAME P12V_OCP_SFF\g
J 0
(-7215 5185);
DISPLAY 0.659574 (-7215 5185);
PAINT MONO (-7215 5185);
DISPLAY INVISIBLE (-7215 5185);
FORCEPROP 1 LAST HDL_POWER P12V_OCP_SFF
J 1
(-7225 5275);
DISPLAY 0.872340 (-7225 5275);
PAINT GREEN (-7225 5275);
FORCEPROP 2 LAST CDS_LIB pure_quanta_power
J 0
(-7225 5225);
DISPLAY INVISIBLE (-7225 5225);
FORCEPROP 1 LAST PATH I3
J 0
(-7175 5250);
DISPLAY 0.872340 (-7175 5250);
PAINT AQUA (-7175 5250);
DISPLAY INVISIBLE (-7175 5250);
FORCEADD OFFPAGE..2
(-375 3675);
FORCEPROP 2 LAST $XR1 82 
J 0
(-186 3639);
DISPLAY 0.638298 (-186 3639);
PAINT MONO (-186 3639);
FORCEPROP 2 LAST $XR0 238 
J 0
(-186 3675);
DISPLAY 0.638298 (-186 3675);
PAINT MONO (-186 3675);
FORCEPROP 2 LAST CDS_LIB standard
J 0
(-375 3675);
DISPLAY INVISIBLE (-375 3675);
FORCEPROP 1 LAST OFFPAGE TRUE
J 0
(-50 3550);
DISPLAY 0.872340 (-50 3550);
DISPLAY INVISIBLE (-50 3550);
FORCEPROP 1 LAST COMMENT_BODY TRUE
J 0
(-420 3580);
DISPLAY 0.872340 (-420 3580);
PAINT GREEN (-420 3580);
DISPLAY INVISIBLE (-420 3580);
FORCEPROP 2 LAST PATH I30
J 0
(-175 3725);
DISPLAY 0.680851 (-175 3725);
DISPLAY INVISIBLE (-175 3725);
FORCEADD Q_RES..1
(-1875 3675);
FORCEPROP 1 LAST LOCATION R1271
J 0
(-2050 3675);
DISPLAY 0.510638 (-2050 3675);
FORCEPROP 0 LAST $SEC 1
J 0
(-1575 3725);
DISPLAY 0.680851 (-1575 3725);
PAINT MONO (-1575 3725);
DISPLAY INVISIBLE (-1575 3725);
FORCEPROP 0 LAST CDS_SEC 1
J 0
(-1575 3725);
DISPLAY 1.021277 (-1575 3725);
DISPLAY INVISIBLE (-1575 3725);
FORCEPROP 1 LASTPIN (-1975 3675) $PN 1
J 0
(-1963 3687);
DISPLAY 0.787234 (-1963 3687);
PAINT MONO (-1963 3687);
FORCEPROP 1 LASTPIN (-1775 3675) $PN 2
J 0
(-1813 3687);
DISPLAY 0.787234 (-1813 3687);
PAINT MONO (-1813 3687);
FORCEPROP 1 LAST VALUE 0
J 2
(-1725 3675);
DISPLAY 0.574468 (-1725 3675);
FORCEPROP 1 LAST MATERIAL CHIP
J 0
(-1700 3675);
DISPLAY 0.574468 (-1700 3675);
FORCEPROP 1 LAST PACK_TYPE 0402LF
J 0
(-1575 3675);
DISPLAY 0.574468 (-1575 3675);
FORCEPROP 2 LAST CDS_LIB pure_quanta
J 0
(-1875 3675);
DISPLAY INVISIBLE (-1875 3675);
FORCEPROP 1 LAST TOLERANCE 5%
J 0
(-2075 3600);
DISPLAY 0.723404 (-2075 3600);
PAINT SKYBLUE (-2075 3600);
DISPLAY INVISIBLE (-2075 3600);
FORCEPROP 1 LAST WATTAGE 1/16W
J 2
(-1800 3600);
DISPLAY 0.723404 (-1800 3600);
PAINT SKYBLUE (-1800 3600);
DISPLAY INVISIBLE (-1800 3600);
FORCEPROP 1 LAST PATH I33
J 0
(-1925 3825);
DISPLAY 0.978723 (-1925 3825);
PAINT WHITE (-1925 3825);
DISPLAY INVISIBLE (-1925 3825);
FORCEPROP 1 LAST PART_NUMBER CS00002JB13
J 0
(-2150 3550);
DISPLAY 0.723404 (-2150 3550);
PAINT WHITE (-2150 3550);
DISPLAY INVISIBLE (-2150 3550);
FORCEADD UNIVERSAL_GND..1
(-2975 2775);
FORCEPROP 3 LASTPIN (-2975 2825) SIG_NAME GND\g
J 0
(-2965 2835);
DISPLAY 0.659574 (-2965 2835);
PAINT MONO (-2965 2835);
DISPLAY INVISIBLE (-2965 2835);
FORCEPROP 2 LAST CDS_LIB pure_quanta_power
J 0
(-2975 2775);
DISPLAY INVISIBLE (-2975 2775);
FORCEPROP 1 LAST HDL_POWER GND
J 1
(-2950 2700);
DISPLAY 0.872340 (-2950 2700);
PAINT GREEN (-2950 2700);
DISPLAY INVISIBLE (-2950 2700);
FORCEPROP 1 LAST PATH I34
J 0
(-2900 2775);
DISPLAY 0.872340 (-2900 2775);
PAINT AQUA (-2900 2775);
DISPLAY INVISIBLE (-2900 2775);
FORCEADD UNIVERSAL_POWER..1
(-4050 4425);
FORCEPROP 3 LASTPIN (-4050 4375) SIG_NAME P3V3_AUX\g
J 0
(-4040 4385);
DISPLAY 0.659574 (-4040 4385);
PAINT MONO (-4040 4385);
DISPLAY INVISIBLE (-4040 4385);
FORCEPROP 1 LAST HDL_POWER P3V3_AUX
J 1
(-4050 4475);
DISPLAY 0.872340 (-4050 4475);
PAINT GREEN (-4050 4475);
FORCEPROP 2 LAST CDS_LIB pure_quanta_power
J 0
(-4050 4425);
DISPLAY INVISIBLE (-4050 4425);
FORCEPROP 1 LAST PATH I35
J 0
(-4000 4450);
DISPLAY 0.872340 (-4000 4450);
PAINT AQUA (-4000 4450);
DISPLAY INVISIBLE (-4000 4450);
FORCEADD Q_CAP..1
(-4300 4025);
FORCEPROP 1 LAST LOCATION C1106
J 0
(-4250 4125);
DISPLAY 0.978723 (-4250 4125);
FORCEPROP 0 LAST $SEC 1
J 0
(-4250 4175);
DISPLAY 0.680851 (-4250 4175);
PAINT MONO (-4250 4175);
DISPLAY INVISIBLE (-4250 4175);
FORCEPROP 0 LAST CDS_SEC 1
J 0
(-4250 4175);
DISPLAY 1.021277 (-4250 4175);
DISPLAY INVISIBLE (-4250 4175);
FORCEPROP 1 LASTPIN (-4300 4125) $PN 1
J 0
(-4290 4105);
DISPLAY 0.787234 (-4290 4105);
PAINT MONO (-4290 4105);
FORCEPROP 1 LASTPIN (-4300 3925) $PN 2
J 0
(-4290 3905);
DISPLAY 0.787234 (-4290 3905);
PAINT MONO (-4290 3905);
FORCEPROP 1 LAST VALUE 0.1UF
J 0
(-4250 4075);
DISPLAY 0.638298 (-4250 4075);
FORCEPROP 1 LAST VOLTAGE 25V
J 0
(-4250 4025);
DISPLAY 0.638298 (-4250 4025);
FORCEPROP 1 LAST TOLERANCE 10%
J 0
(-4250 3975);
DISPLAY 0.638298 (-4250 3975);
FORCEPROP 1 LAST PACK_TYPE 0402
J 0
(-4250 3875);
DISPLAY 0.638298 (-4250 3875);
FORCEPROP 1 LAST MATERIAL X7R
J 0
(-4250 3925);
DISPLAY 0.638298 (-4250 3925);
FORCEPROP 2 LAST CDS_LIB pure_quanta
J 0
(-4300 4025);
DISPLAY INVISIBLE (-4300 4025);
FORCEPROP 1 LAST PATH I36
J 0
(-4250 4175);
DISPLAY 0.978723 (-4250 4175);
PAINT WHITE (-4250 4175);
DISPLAY INVISIBLE (-4250 4175);
FORCEPROP 1 LAST PART_NUMBER CH4104K1B00
J 0
(-4250 3875);
DISPLAY 0.808511 (-4250 3875);
DISPLAY INVISIBLE (-4250 3875);
FORCEADD UNIVERSAL_GND..1
(-4300 3800);
FORCEPROP 3 LASTPIN (-4300 3850) SIG_NAME GND\g
J 0
(-4290 3860);
DISPLAY 0.659574 (-4290 3860);
PAINT MONO (-4290 3860);
DISPLAY INVISIBLE (-4290 3860);
FORCEPROP 2 LAST CDS_LIB pure_quanta_power
J 0
(-4300 3800);
DISPLAY INVISIBLE (-4300 3800);
FORCEPROP 1 LAST HDL_POWER GND
J 1
(-4275 3725);
DISPLAY 0.872340 (-4275 3725);
PAINT GREEN (-4275 3725);
DISPLAY INVISIBLE (-4275 3725);
FORCEPROP 1 LAST PATH I37
J 0
(-4225 3800);
DISPLAY 0.872340 (-4225 3800);
PAINT AQUA (-4225 3800);
DISPLAY INVISIBLE (-4225 3800);
FORCEADD UNIVERSAL_POWER..1
(-4900 4325);
FORCEPROP 3 LASTPIN (-4900 4275) SIG_NAME P3V3_AUX\g
J 0
(-4890 4285);
DISPLAY 0.659574 (-4890 4285);
PAINT MONO (-4890 4285);
DISPLAY INVISIBLE (-4890 4285);
FORCEPROP 1 LAST HDL_POWER P3V3_AUX
J 1
(-4900 4375);
DISPLAY 0.872340 (-4900 4375);
PAINT GREEN (-4900 4375);
FORCEPROP 2 LAST CDS_LIB pure_quanta_power
J 0
(-4900 4325);
DISPLAY INVISIBLE (-4900 4325);
FORCEPROP 1 LAST PATH I38
J 0
(-4850 4350);
DISPLAY 0.872340 (-4850 4350);
PAINT AQUA (-4850 4350);
DISPLAY INVISIBLE (-4850 4350);
FORCEADD Q_RES..2
(-4900 4025);
FORCEPROP 1 LAST LOCATION R1322
J 0
(-4855 4150);
DISPLAY 0.978723 (-4855 4150);
FORCEPROP 0 LAST $SEC 1
J 0
(-4850 4200);
DISPLAY 0.680851 (-4850 4200);
PAINT MONO (-4850 4200);
DISPLAY INVISIBLE (-4850 4200);
FORCEPROP 0 LAST CDS_SEC 1
J 0
(-4850 4200);
DISPLAY 1.021277 (-4850 4200);
DISPLAY INVISIBLE (-4850 4200);
FORCEPROP 1 LASTPIN (-4900 4125) $PN 1
J 0
(-4895 4087);
DISPLAY 0.787234 (-4895 4087);
PAINT MONO (-4895 4087);
FORCEPROP 1 LASTPIN (-4900 3925) $PN 2
J 0
(-4895 3935);
DISPLAY 0.787234 (-4895 3935);
PAINT MONO (-4895 3935);
FORCEPROP 1 LAST MATERIAL CHIP
J 0
(-4860 3950);
DISPLAY 0.510638 (-4860 3950);
FORCEPROP 1 LAST PACK_TYPE 0402LF
J 0
(-4860 3850);
DISPLAY 0.510638 (-4860 3850);
FORCEPROP 1 LAST WATTAGE 1/16W
J 0
(-4860 4000);
DISPLAY 0.510638 (-4860 4000);
FORCEPROP 1 LAST VALUE 4.7K
J 0
(-4855 4100);
DISPLAY 0.510638 (-4855 4100);
FORCEPROP 1 LAST TOLERANCE 1%
J 0
(-4855 4050);
DISPLAY 0.510638 (-4855 4050);
FORCEPROP 2 LAST CDS_LIB pure_quanta
J 0
(-4900 4025);
DISPLAY INVISIBLE (-4900 4025);
FORCEPROP 1 LAST PATH I39
J 0
(-4850 4200);
DISPLAY 0.978723 (-4850 4200);
PAINT WHITE (-4850 4200);
DISPLAY INVISIBLE (-4850 4200);
FORCEPROP 1 LAST PART_NUMBER CS24702FB06
J 0
(-4860 3900);
DISPLAY 0.510638 (-4860 3900);
DISPLAY INVISIBLE (-4860 3900);
FORCEADD UNIVERSAL_GND..1
(-7625 5375);
FORCEPROP 3 LASTPIN (-7625 5425) SIG_NAME GND\g
J 0
(-7615 5435);
DISPLAY 0.659574 (-7615 5435);
PAINT MONO (-7615 5435);
DISPLAY INVISIBLE (-7615 5435);
FORCEPROP 2 LAST CDS_LIB pure_quanta_power
J 0
(-7625 5375);
DISPLAY INVISIBLE (-7625 5375);
FORCEPROP 1 LAST HDL_POWER GND
J 1
(-7600 5300);
DISPLAY 0.872340 (-7600 5300);
PAINT GREEN (-7600 5300);
DISPLAY INVISIBLE (-7600 5300);
FORCEPROP 1 LAST PATH I4
J 0
(-7550 5375);
DISPLAY 0.872340 (-7550 5375);
PAINT AQUA (-7550 5375);
DISPLAY INVISIBLE (-7550 5375);
FORCEADD Q_RES..1
(-5200 3375);
FORCEPROP 1 LAST LOCATION R1277
J 0
(-5475 3375);
DISPLAY 0.787234 (-5475 3375);
FORCEPROP 0 LAST $SEC 1
J 0
(-4900 3425);
DISPLAY 0.680851 (-4900 3425);
PAINT MONO (-4900 3425);
DISPLAY INVISIBLE (-4900 3425);
FORCEPROP 0 LAST CDS_SEC 1
J 0
(-4900 3425);
DISPLAY 0.680851 (-4900 3425);
DISPLAY INVISIBLE (-4900 3425);
FORCEPROP 1 LASTPIN (-5300 3375) $PN 1
J 0
(-5288 3387);
DISPLAY 0.787234 (-5288 3387);
PAINT MONO (-5288 3387);
FORCEPROP 1 LASTPIN (-5100 3375) $PN 2
J 0
(-5138 3387);
DISPLAY 0.787234 (-5138 3387);
PAINT MONO (-5138 3387);
FORCEPROP 1 LAST VALUE 0
J 2
(-5050 3375);
DISPLAY 0.510638 (-5050 3375);
FORCEPROP 1 LAST TOLERANCE 5%
J 0
(-5025 3375);
DISPLAY 0.510638 (-5025 3375);
FORCEPROP 1 LAST MATERIAL CHIP
J 0
(-4975 3375);
DISPLAY 0.510638 (-4975 3375);
FORCEPROP 2 LAST CDS_LIB pure_quanta
J 0
(-5200 3375);
DISPLAY INVISIBLE (-5200 3375);
FORCEPROP 1 LAST WATTAGE 1/16W
J 2
(-5025 3450);
DISPLAY 0.510638 (-5025 3450);
DISPLAY INVISIBLE (-5025 3450);
FORCEPROP 1 LAST PACK_TYPE 0402LF
J 0
(-5300 3450);
DISPLAY 0.404255 (-5300 3450);
DISPLAY INVISIBLE (-5300 3450);
FORCEPROP 1 LAST PATH I41
J 0
(-5250 3525);
DISPLAY 0.978723 (-5250 3525);
PAINT WHITE (-5250 3525);
DISPLAY INVISIBLE (-5250 3525);
FORCEPROP 1 LAST PART_NUMBER CS00002JB13
J 0
(-5300 3425);
DISPLAY 0.404255 (-5300 3425);
DISPLAY INVISIBLE (-5300 3425);
FORCEADD Q_RES..1
(-5200 3425);
FORCEPROP 1 LAST LOCATION R1274
J 0
(-5475 3425);
DISPLAY 0.787234 (-5475 3425);
FORCEPROP 0 LAST $SEC 1
J 0
(-5025 3525);
DISPLAY 0.680851 (-5025 3525);
PAINT MONO (-5025 3525);
DISPLAY INVISIBLE (-5025 3525);
FORCEPROP 0 LAST CDS_SEC 1
J 0
(-5025 3525);
DISPLAY 0.680851 (-5025 3525);
DISPLAY INVISIBLE (-5025 3525);
FORCEPROP 1 LASTPIN (-5300 3425) $PN 1
J 0
(-5288 3437);
DISPLAY 0.787234 (-5288 3437);
PAINT MONO (-5288 3437);
FORCEPROP 1 LASTPIN (-5100 3425) $PN 2
J 0
(-5138 3437);
DISPLAY 0.787234 (-5138 3437);
PAINT MONO (-5138 3437);
FORCEPROP 1 LAST PACK_TYPE 0402LF
J 0
(-5300 3500);
DISPLAY 0.404255 (-5300 3500);
FORCEPROP 1 LAST MATERIAL CHIP
J 0
(-4975 3425);
DISPLAY 0.510638 (-4975 3425);
FORCEPROP 1 LAST VALUE 0
J 2
(-5050 3425);
DISPLAY 0.510638 (-5050 3425);
FORCEPROP 1 LAST TOLERANCE 5%
J 0
(-5025 3425);
DISPLAY 0.510638 (-5025 3425);
FORCEPROP 1 LAST WATTAGE 1/16W
J 2
(-5025 3500);
DISPLAY 0.510638 (-5025 3500);
FORCEPROP 2 LAST CDS_LIB pure_quanta
J 0
(-5200 3425);
DISPLAY INVISIBLE (-5200 3425);
FORCEPROP 1 LAST PATH I42
J 0
(-5250 3575);
DISPLAY 0.978723 (-5250 3575);
PAINT WHITE (-5250 3575);
DISPLAY INVISIBLE (-5250 3575);
FORCEPROP 1 LAST PART_NUMBER CS00002JB13
J 0
(-5300 3475);
DISPLAY 0.404255 (-5300 3475);
DISPLAY INVISIBLE (-5300 3475);
FORCEADD Q_RES..1
(-5175 2825);
FORCEPROP 1 LAST LOCATION R1291
J 0
(-5425 2825);
DISPLAY 0.638298 (-5425 2825);
FORCEPROP 0 LAST $SEC 1
J 0
(-5325 2925);
DISPLAY 0.680851 (-5325 2925);
PAINT MONO (-5325 2925);
DISPLAY INVISIBLE (-5325 2925);
FORCEPROP 0 LAST CDS_SEC 1
J 0
(-5325 2925);
DISPLAY 1.021277 (-5325 2925);
DISPLAY INVISIBLE (-5325 2925);
FORCEPROP 1 LASTPIN (-5275 2825) $PN 1
J 0
(-5263 2837);
DISPLAY 0.787234 (-5263 2837);
PAINT MONO (-5263 2837);
FORCEPROP 1 LASTPIN (-5075 2825) $PN 2
J 0
(-5113 2837);
DISPLAY 0.787234 (-5113 2837);
PAINT MONO (-5113 2837);
FORCEPROP 1 LAST TOLERANCE 1%
J 0
(-5125 2775);
DISPLAY 0.638298 (-5125 2775);
FORCEPROP 1 LAST WATTAGE 1/16W
J 2
(-5175 2725);
DISPLAY 0.638298 (-5175 2725);
FORCEPROP 1 LAST VALUE 10
J 2
(-5225 2775);
DISPLAY 0.638298 (-5225 2775);
FORCEPROP 1 LAST MATERIAL CHIP
J 0
(-5150 2725);
DISPLAY 0.638298 (-5150 2725);
FORCEPROP 1 LAST PACK_TYPE 0402LF
J 0
(-5050 2775);
DISPLAY 0.638298 (-5050 2775);
FORCEPROP 2 LAST CDS_LIB pure_quanta
J 0
(-5175 2825);
DISPLAY INVISIBLE (-5175 2825);
FORCEPROP 1 LAST PATH I43
J 0
(-5225 2975);
DISPLAY 0.978723 (-5225 2975);
PAINT WHITE (-5225 2975);
DISPLAY INVISIBLE (-5225 2975);
FORCEPROP 1 LAST PART_NUMBER CS01002FB07
J 0
(-5325 2875);
DISPLAY 0.638298 (-5325 2875);
DISPLAY INVISIBLE (-5325 2875);
FORCEADD Q_RES..1
(-6000 3750);
FORCEPROP 1 LAST LOCATION R1307
J 0
(-6125 3750);
DISPLAY 0.638298 (-6125 3750);
FORCEPROP 0 LAST $SEC 1
J 0
(-6125 3800);
DISPLAY 0.680851 (-6125 3800);
PAINT MONO (-6125 3800);
DISPLAY INVISIBLE (-6125 3800);
FORCEPROP 0 LAST CDS_SEC 1
J 0
(-6125 3800);
DISPLAY 1.021277 (-6125 3800);
DISPLAY INVISIBLE (-6125 3800);
FORCEPROP 1 LASTPIN (-6100 3750) $PN 1
J 0
(-6088 3762);
DISPLAY 0.787234 (-6088 3762);
PAINT MONO (-6088 3762);
FORCEPROP 1 LASTPIN (-5900 3750) $PN 2
J 0
(-5938 3762);
DISPLAY 0.787234 (-5938 3762);
PAINT MONO (-5938 3762);
FORCEPROP 1 LAST WATTAGE 1/16W
J 2
(-5675 3750);
DISPLAY 0.510638 (-5675 3750);
FORCEPROP 1 LAST MATERIAL EMPTY
J 0
(-5625 3750);
DISPLAY 0.510638 (-5625 3750);
PAINT RED (-5625 3750);
FORCEPROP 1 LAST VALUE 4.7K
J 2
(-5800 3750);
DISPLAY 0.510638 (-5800 3750);
FORCEPROP 1 LAST TOLERANCE 1%
J 0
(-5675 3750);
DISPLAY 0.510638 (-5675 3750);
FORCEPROP 1 LAST PACK_TYPE 0402LF
J 0
(-5525 3750);
DISPLAY 0.510638 (-5525 3750);
FORCEPROP 2 LAST CDS_LIB pure_quanta
J 0
(-6000 3750);
DISPLAY INVISIBLE (-6000 3750);
FORCEPROP 1 LAST PATH I44
J 0
(-6050 3900);
DISPLAY 0.978723 (-6050 3900);
PAINT WHITE (-6050 3900);
DISPLAY INVISIBLE (-6050 3900);
FORCEPROP 1 LAST PART_NUMBER CS24702FB06
J 0
(-6425 3750);
DISPLAY 0.510638 (-6425 3750);
DISPLAY INVISIBLE (-6425 3750);
FORCEADD Q_RES..1
(-6000 3675);
FORCEPROP 1 LAST LOCATION R1310
J 0
(-6125 3675);
DISPLAY 0.638298 (-6125 3675);
FORCEPROP 0 LAST $SEC 1
J 0
(-6125 3725);
DISPLAY 0.680851 (-6125 3725);
PAINT MONO (-6125 3725);
DISPLAY INVISIBLE (-6125 3725);
FORCEPROP 0 LAST CDS_SEC 1
J 0
(-6125 3725);
DISPLAY 1.021277 (-6125 3725);
DISPLAY INVISIBLE (-6125 3725);
FORCEPROP 1 LASTPIN (-6100 3675) $PN 1
J 0
(-6088 3687);
DISPLAY 0.787234 (-6088 3687);
PAINT MONO (-6088 3687);
FORCEPROP 1 LASTPIN (-5900 3675) $PN 2
J 0
(-5938 3687);
DISPLAY 0.787234 (-5938 3687);
PAINT MONO (-5938 3687);
FORCEPROP 1 LAST PACK_TYPE 0402LF
J 0
(-5525 3675);
DISPLAY 0.510638 (-5525 3675);
FORCEPROP 1 LAST MATERIAL EMPTY
J 0
(-5625 3675);
DISPLAY 0.510638 (-5625 3675);
PAINT RED (-5625 3675);
FORCEPROP 1 LAST WATTAGE 1/16W
J 2
(-5675 3675);
DISPLAY 0.510638 (-5675 3675);
FORCEPROP 1 LAST TOLERANCE 1%
J 0
(-5675 3675);
DISPLAY 0.510638 (-5675 3675);
FORCEPROP 1 LAST VALUE 4.7K
J 2
(-5800 3675);
DISPLAY 0.510638 (-5800 3675);
FORCEPROP 2 LAST CDS_LIB pure_quanta
J 0
(-6000 3675);
DISPLAY INVISIBLE (-6000 3675);
FORCEPROP 1 LAST PATH I45
J 0
(-6050 3825);
DISPLAY 0.978723 (-6050 3825);
PAINT WHITE (-6050 3825);
DISPLAY INVISIBLE (-6050 3825);
FORCEPROP 1 LAST PART_NUMBER CS24702FB06
J 0
(-6425 3675);
DISPLAY 0.510638 (-6425 3675);
DISPLAY INVISIBLE (-6425 3675);
FORCEADD UNIVERSAL_POWER..1
(-6725 3925);
FORCEPROP 3 LASTPIN (-6725 3875) SIG_NAME P12V_OCP_V3_2\g
J 0
(-6715 3885);
DISPLAY 0.659574 (-6715 3885);
PAINT MONO (-6715 3885);
DISPLAY INVISIBLE (-6715 3885);
FORCEPROP 1 LAST HDL_POWER P12V_OCP_V3_2
J 1
(-6725 3975);
DISPLAY 0.872340 (-6725 3975);
PAINT GREEN (-6725 3975);
FORCEPROP 2 LAST CDS_LIB pure_quanta_power
J 0
(-6725 3925);
DISPLAY INVISIBLE (-6725 3925);
FORCEPROP 1 LAST PATH I46
J 0
(-6675 3950);
DISPLAY 0.872340 (-6675 3950);
PAINT AQUA (-6675 3950);
DISPLAY INVISIBLE (-6675 3950);
FORCEADD UNIVERSAL_GND..1
(-6425 3500);
FORCEPROP 3 LASTPIN (-6425 3550) SIG_NAME GND\g
J 0
(-6415 3560);
DISPLAY 0.659574 (-6415 3560);
PAINT MONO (-6415 3560);
DISPLAY INVISIBLE (-6415 3560);
FORCEPROP 2 LAST CDS_LIB pure_quanta_power
J 0
(-6425 3500);
DISPLAY INVISIBLE (-6425 3500);
FORCEPROP 1 LAST HDL_POWER GND
J 1
(-6400 3425);
DISPLAY 0.872340 (-6400 3425);
PAINT GREEN (-6400 3425);
DISPLAY INVISIBLE (-6400 3425);
FORCEPROP 1 LAST PATH I47
J 0
(-6350 3500);
DISPLAY 0.872340 (-6350 3500);
PAINT AQUA (-6350 3500);
DISPLAY INVISIBLE (-6350 3500);
FORCEADD OFFPAGE..1
(-6400 3425);
FORCEPROP 2 LAST $XR0 252 
J 0
(-6652 3425);
DISPLAY 0.638298 (-6652 3425);
PAINT MONO (-6652 3425);
FORCEPROP 2 LAST CDS_LIB standard
J 0
(-6400 3425);
DISPLAY INVISIBLE (-6400 3425);
FORCEPROP 1 LAST OFFPAGE TRUE
J 0
(-6075 3300);
DISPLAY 0.872340 (-6075 3300);
DISPLAY INVISIBLE (-6075 3300);
FORCEPROP 1 LAST COMMENT_BODY TRUE
J 0
(-6275 3325);
DISPLAY 0.872340 (-6275 3325);
PAINT GREEN (-6275 3325);
DISPLAY INVISIBLE (-6275 3325);
FORCEPROP 2 LAST PATH I48
J 0
(-6650 3475);
DISPLAY 0.680851 (-6650 3475);
DISPLAY INVISIBLE (-6650 3475);
FORCEADD OFFPAGE..3
R 2
(-6400 3375);
FORCEPROP 2 LAST $XR0 252 
J 0
(-6680 3375);
DISPLAY 0.638298 (-6680 3375);
PAINT MONO (-6680 3375);
FORCEPROP 2 LAST CDS_LIB standard
J 2
(-6400 3375);
PAINT MONO (-6400 3375);
DISPLAY INVISIBLE (-6400 3375);
FORCEPROP 1 LAST OFFPAGE TRUE
J 2
(-6725 3250);
DISPLAY 0.872340 (-6725 3250);
DISPLAY INVISIBLE (-6725 3250);
FORCEPROP 1 LAST COMMENT_BODY TRUE
J 2
(-6350 3275);
DISPLAY 0.872340 (-6350 3275);
PAINT GREEN (-6350 3275);
DISPLAY INVISIBLE (-6350 3275);
FORCEPROP 2 LAST PATH I49
J 0
(-6675 3425);
DISPLAY 0.680851 (-6675 3425);
DISPLAY INVISIBLE (-6675 3425);
FORCEADD Q_CAP..1
(-7625 5650);
FORCEPROP 1 LAST LOCATION C1108
J 0
(-7575 5750);
DISPLAY 0.978723 (-7575 5750);
FORCEPROP 0 LAST $SEC 1
J 0
(-7575 5800);
DISPLAY 0.680851 (-7575 5800);
PAINT MONO (-7575 5800);
DISPLAY INVISIBLE (-7575 5800);
FORCEPROP 0 LAST CDS_SEC 1
J 0
(-7575 5800);
DISPLAY 1.021277 (-7575 5800);
DISPLAY INVISIBLE (-7575 5800);
FORCEPROP 1 LASTPIN (-7625 5750) $PN 1
J 0
(-7615 5730);
DISPLAY 0.787234 (-7615 5730);
PAINT MONO (-7615 5730);
FORCEPROP 1 LASTPIN (-7625 5550) $PN 2
J 0
(-7615 5530);
DISPLAY 0.787234 (-7615 5530);
PAINT MONO (-7615 5530);
FORCEPROP 1 LAST VALUE 0.1UF
J 0
(-7575 5700);
DISPLAY 0.638298 (-7575 5700);
FORCEPROP 1 LAST MATERIAL X7R
J 0
(-7575 5550);
DISPLAY 0.638298 (-7575 5550);
FORCEPROP 1 LAST PACK_TYPE 0402
J 0
(-7575 5500);
DISPLAY 0.638298 (-7575 5500);
FORCEPROP 1 LAST TOLERANCE 10%
J 0
(-7575 5600);
DISPLAY 0.638298 (-7575 5600);
FORCEPROP 1 LAST VOLTAGE 25V
J 0
(-7575 5650);
DISPLAY 0.638298 (-7575 5650);
FORCEPROP 2 LAST CDS_LIB pure_quanta
J 0
(-7625 5650);
DISPLAY INVISIBLE (-7625 5650);
FORCEPROP 1 LAST PATH I5
J 0
(-7575 5800);
DISPLAY 0.978723 (-7575 5800);
PAINT WHITE (-7575 5800);
DISPLAY INVISIBLE (-7575 5800);
FORCEPROP 1 LAST PART_NUMBER CH4104K1B00
J 0
(-7575 5500);
DISPLAY 0.808511 (-7575 5500);
DISPLAY INVISIBLE (-7575 5500);
FORCEADD UNIVERSAL_POWER..1
(-6575 3175);
FORCEPROP 3 LASTPIN (-6575 3125) SIG_NAME P12V_OCP_V3_2\g
J 0
(-6565 3135);
DISPLAY 0.659574 (-6565 3135);
PAINT MONO (-6565 3135);
DISPLAY INVISIBLE (-6565 3135);
FORCEPROP 1 LAST HDL_POWER P12V_OCP_V3_2
J 1
(-6575 3225);
DISPLAY 0.872340 (-6575 3225);
PAINT GREEN (-6575 3225);
FORCEPROP 2 LAST CDS_LIB pure_quanta_power
J 0
(-6575 3175);
DISPLAY INVISIBLE (-6575 3175);
FORCEPROP 1 LAST PATH I50
J 0
(-6525 3200);
DISPLAY 0.872340 (-6525 3200);
PAINT AQUA (-6525 3200);
DISPLAY INVISIBLE (-6525 3200);
FORCEADD Q_CAP..1
(-6975 3600);
FORCEPROP 1 LAST LOCATION C1109
J 0
(-6925 3700);
DISPLAY 0.978723 (-6925 3700);
FORCEPROP 0 LAST $SEC 1
J 0
(-6925 3750);
DISPLAY 0.680851 (-6925 3750);
PAINT MONO (-6925 3750);
DISPLAY INVISIBLE (-6925 3750);
FORCEPROP 0 LAST CDS_SEC 1
J 0
(-6925 3750);
DISPLAY 1.021277 (-6925 3750);
DISPLAY INVISIBLE (-6925 3750);
FORCEPROP 1 LASTPIN (-6975 3700) $PN 1
J 0
(-6965 3680);
DISPLAY 0.787234 (-6965 3680);
PAINT MONO (-6965 3680);
FORCEPROP 1 LASTPIN (-6975 3500) $PN 2
J 0
(-6965 3480);
DISPLAY 0.787234 (-6965 3480);
PAINT MONO (-6965 3480);
FORCEPROP 1 LAST TOLERANCE 10%
J 0
(-6925 3550);
DISPLAY 0.638298 (-6925 3550);
FORCEPROP 1 LAST VOLTAGE 25V
J 0
(-6925 3600);
DISPLAY 0.638298 (-6925 3600);
FORCEPROP 1 LAST VALUE 0.1UF
J 0
(-6925 3650);
DISPLAY 0.638298 (-6925 3650);
FORCEPROP 1 LAST PACK_TYPE 0402
J 0
(-6925 3450);
DISPLAY 0.638298 (-6925 3450);
FORCEPROP 1 LAST MATERIAL X7R
J 0
(-6925 3500);
DISPLAY 0.638298 (-6925 3500);
FORCEPROP 2 LAST CDS_LIB pure_quanta
J 0
(-6975 3600);
DISPLAY INVISIBLE (-6975 3600);
FORCEPROP 1 LAST PATH I51
J 0
(-6925 3750);
DISPLAY 0.978723 (-6925 3750);
PAINT WHITE (-6925 3750);
DISPLAY INVISIBLE (-6925 3750);
FORCEPROP 1 LAST PART_NUMBER CH4104K1B00
J 0
(-6925 3450);
DISPLAY 0.808511 (-6925 3450);
DISPLAY INVISIBLE (-6925 3450);
FORCEADD UNIVERSAL_GND..1
(-6975 3325);
FORCEPROP 3 LASTPIN (-6975 3375) SIG_NAME GND\g
J 0
(-6965 3385);
DISPLAY 0.659574 (-6965 3385);
PAINT MONO (-6965 3385);
DISPLAY INVISIBLE (-6965 3385);
FORCEPROP 2 LAST CDS_LIB pure_quanta_power
J 0
(-6975 3325);
DISPLAY INVISIBLE (-6975 3325);
FORCEPROP 1 LAST HDL_POWER GND
J 1
(-6950 3250);
DISPLAY 0.872340 (-6950 3250);
PAINT GREEN (-6950 3250);
DISPLAY INVISIBLE (-6950 3250);
FORCEPROP 1 LAST PATH I52
J 0
(-6900 3325);
DISPLAY 0.872340 (-6900 3325);
PAINT AQUA (-6900 3325);
DISPLAY INVISIBLE (-6900 3325);
FORCEADD Q_RES..1
(-7075 3025);
FORCEPROP 1 LAST LOCATION R1325
J 0
(-7125 3075);
DISPLAY 0.978723 (-7125 3075);
FORCEPROP 0 LAST $SEC 1
J 0
(-7125 3125);
DISPLAY 0.680851 (-7125 3125);
PAINT MONO (-7125 3125);
DISPLAY INVISIBLE (-7125 3125);
FORCEPROP 0 LAST CDS_SEC 1
J 0
(-7125 3125);
DISPLAY 1.021277 (-7125 3125);
DISPLAY INVISIBLE (-7125 3125);
FORCEPROP 1 LASTPIN (-7175 3025) $PN 1
J 0
(-7163 3037);
DISPLAY 0.787234 (-7163 3037);
PAINT MONO (-7163 3037);
FORCEPROP 1 LASTPIN (-6975 3025) $PN 2
J 0
(-7013 3037);
DISPLAY 0.787234 (-7013 3037);
PAINT MONO (-7013 3037);
FORCEPROP 1 LAST WATTAGE 2W
J 2
(-7100 2875);
DISPLAY 0.510638 (-7100 2875);
FORCEPROP 1 LAST VALUE 0.002
J 2
(-7100 2925);
DISPLAY 0.510638 (-7100 2925);
FORCEPROP 1 LAST TOLERANCE 1%
J 0
(-7075 2925);
DISPLAY 0.510638 (-7075 2925);
FORCEPROP 1 LAST MATERIAL CHIP
J 0
(-7075 2875);
DISPLAY 0.510638 (-7075 2875);
FORCEPROP 1 LAST PACK_TYPE 2512LF
J 0
(-7000 2925);
DISPLAY 0.510638 (-7000 2925);
FORCEPROP 2 LAST CDS_LIB pure_quanta
J 0
(-7075 3025);
DISPLAY INVISIBLE (-7075 3025);
FORCEPROP 1 LAST PATH I53
J 0
(-7125 3175);
DISPLAY 0.978723 (-7125 3175);
PAINT WHITE (-7125 3175);
DISPLAY INVISIBLE (-7125 3175);
FORCEPROP 1 LAST PART_NUMBER CS+002AFR06
J 0
(-7200 2975);
DISPLAY 0.510638 (-7200 2975);
DISPLAY INVISIBLE (-7200 2975);
FORCEADD Q_CAP..1
(-4825 2675);
FORCEPROP 1 LAST LOCATION C1112
J 0
(-4775 2775);
DISPLAY 0.978723 (-4775 2775);
FORCEPROP 0 LAST $SEC 1
J 0
(-4775 2825);
DISPLAY 0.680851 (-4775 2825);
PAINT MONO (-4775 2825);
DISPLAY INVISIBLE (-4775 2825);
FORCEPROP 0 LAST CDS_SEC 1
J 0
(-4775 2825);
DISPLAY 1.021277 (-4775 2825);
DISPLAY INVISIBLE (-4775 2825);
FORCEPROP 1 LASTPIN (-4825 2775) $PN 1
J 0
(-4815 2755);
DISPLAY 0.787234 (-4815 2755);
PAINT MONO (-4815 2755);
FORCEPROP 1 LASTPIN (-4825 2575) $PN 2
J 0
(-4815 2555);
DISPLAY 0.787234 (-4815 2555);
PAINT MONO (-4815 2555);
FORCEPROP 1 LAST VOLTAGE 25V
J 0
(-4775 2700);
DISPLAY 0.510638 (-4775 2700);
FORCEPROP 1 LAST PACK_TYPE 0402
J 0
(-4775 2600);
DISPLAY 0.510638 (-4775 2600);
FORCEPROP 1 LAST MATERIAL X7R
J 0
(-4775 2650);
DISPLAY 0.510638 (-4775 2650);
FORCEPROP 1 LAST TOLERANCE 10%
J 0
(-4775 2675);
DISPLAY 0.510638 (-4775 2675);
FORCEPROP 1 LAST VALUE 0.1UF
J 0
(-4775 2725);
DISPLAY 0.510638 (-4775 2725);
FORCEPROP 2 LAST CDS_LIB pure_quanta
J 0
(-4825 2675);
DISPLAY INVISIBLE (-4825 2675);
FORCEPROP 1 LAST PATH I54
J 0
(-4775 2825);
DISPLAY 0.978723 (-4775 2825);
PAINT WHITE (-4775 2825);
DISPLAY INVISIBLE (-4775 2825);
FORCEPROP 1 LAST PART_NUMBER CH4104K1B00
J 0
(-4775 2625);
DISPLAY 0.510638 (-4775 2625);
DISPLAY INVISIBLE (-4775 2625);
FORCEADD Q_RES..1
(-5175 2550);
FORCEPROP 1 LAST LOCATION R1302
J 0
(-5425 2550);
DISPLAY 0.638298 (-5425 2550);
FORCEPROP 0 LAST $SEC 1
J 0
(-5325 2650);
DISPLAY 0.680851 (-5325 2650);
PAINT MONO (-5325 2650);
DISPLAY INVISIBLE (-5325 2650);
FORCEPROP 0 LAST CDS_SEC 1
J 0
(-5325 2650);
DISPLAY 1.021277 (-5325 2650);
DISPLAY INVISIBLE (-5325 2650);
FORCEPROP 1 LASTPIN (-5275 2550) $PN 1
J 0
(-5263 2562);
DISPLAY 0.787234 (-5263 2562);
PAINT MONO (-5263 2562);
FORCEPROP 1 LASTPIN (-5075 2550) $PN 2
J 0
(-5113 2562);
DISPLAY 0.787234 (-5113 2562);
PAINT MONO (-5113 2562);
FORCEPROP 1 LAST VALUE 10
J 2
(-5225 2500);
DISPLAY 0.638298 (-5225 2500);
FORCEPROP 1 LAST MATERIAL CHIP
J 0
(-5150 2450);
DISPLAY 0.638298 (-5150 2450);
FORCEPROP 1 LAST TOLERANCE 1%
J 0
(-5125 2500);
DISPLAY 0.638298 (-5125 2500);
FORCEPROP 1 LAST PACK_TYPE 0402LF
J 0
(-5050 2500);
DISPLAY 0.638298 (-5050 2500);
FORCEPROP 1 LAST WATTAGE 1/16W
J 2
(-5175 2450);
DISPLAY 0.638298 (-5175 2450);
FORCEPROP 2 LAST CDS_LIB pure_quanta
J 0
(-5175 2550);
DISPLAY INVISIBLE (-5175 2550);
FORCEPROP 1 LAST PATH I55
J 0
(-5225 2700);
DISPLAY 0.978723 (-5225 2700);
PAINT WHITE (-5225 2700);
DISPLAY INVISIBLE (-5225 2700);
FORCEPROP 1 LAST PART_NUMBER CS01002FB07
J 0
(-5325 2600);
DISPLAY 0.638298 (-5325 2600);
DISPLAY INVISIBLE (-5325 2600);
FORCEADD UNIVERSAL_POWER..1
(-7650 3175);
FORCEPROP 3 LASTPIN (-7650 3125) SIG_NAME P12V_OCP_V3_2_R\g
J 0
(-7640 3135);
DISPLAY 0.659574 (-7640 3135);
PAINT MONO (-7640 3135);
DISPLAY INVISIBLE (-7640 3135);
FORCEPROP 1 LAST HDL_POWER P12V_OCP_V3_2_R
J 1
(-7650 3225);
DISPLAY 0.872340 (-7650 3225);
PAINT GREEN (-7650 3225);
FORCEPROP 2 LAST CDS_LIB pure_quanta_power
J 0
(-7650 3175);
DISPLAY INVISIBLE (-7650 3175);
FORCEPROP 1 LAST PATH I56
J 0
(-7600 3200);
DISPLAY 0.872340 (-7600 3200);
PAINT AQUA (-7600 3200);
DISPLAY INVISIBLE (-7600 3200);
FORCEADD ISL28022FRZT..1
(-4750 1150);
FORCEPROP 1 LAST LOCATION U52
J 0
(-5045 1731);
DISPLAY 0.723404 (-5045 1731);
PAINT GREEN (-5045 1731);
FORCEPROP 2 LAST SEC 1
J 0
(-5025 1875);
DISPLAY 0.680851 (-5025 1875);
PAINT MONO (-5025 1875);
DISPLAY INVISIBLE (-5025 1875);
FORCEPROP 2 LASTPIN (-5200 1250) $PN 2
J 2
(-5210 1260);
DISPLAY 0.680851 (-5210 1260);
PAINT MONO (-5210 1260);
FORCEPROP 2 LASTPIN (-5200 1300) $PN 1
J 2
(-5210 1310);
DISPLAY 0.680851 (-5210 1310);
PAINT MONO (-5210 1310);
FORCEPROP 2 LASTPIN (-4300 1400) $PN 3
J 0
(-4290 1410);
DISPLAY 0.680851 (-4290 1410);
PAINT MONO (-4290 1410);
FORCEPROP 2 LASTPIN (-4300 950) $PN 10
J 0
(-4290 960);
DISPLAY 0.680851 (-4290 960);
PAINT MONO (-4290 960);
FORCEPROP 2 LASTPIN (-4300 1300) $PN 6
J 0
(-4290 1310);
DISPLAY 0.680851 (-4290 1310);
PAINT MONO (-4290 1310);
FORCEPROP 2 LASTPIN (-4300 1250) $PN 7
J 0
(-4290 1260);
DISPLAY 0.680851 (-4290 1260);
PAINT MONO (-4290 1260);
FORCEPROP 2 LASTPIN (-4300 1200) $PN 8
J 0
(-4290 1210);
DISPLAY 0.680851 (-4290 1210);
PAINT MONO (-4290 1210);
FORCEPROP 2 LASTPIN (-4300 1150) $PN 14
J 0
(-4290 1160);
DISPLAY 0.680851 (-4290 1160);
PAINT MONO (-4290 1160);
FORCEPROP 2 LASTPIN (-4300 1100) $PN 15
J 0
(-4290 1110);
DISPLAY 0.680851 (-4290 1110);
PAINT MONO (-4290 1110);
FORCEPROP 2 LASTPIN (-4300 1050) $PN 16
J 0
(-4290 1060);
DISPLAY 0.680851 (-4290 1060);
PAINT MONO (-4290 1060);
FORCEPROP 2 LASTPIN (-5200 1150) $PN 5
J 2
(-5210 1160);
DISPLAY 0.680851 (-5210 1160);
PAINT MONO (-5210 1160);
FORCEPROP 2 LASTPIN (-5200 1100) $PN 4
J 2
(-5210 1110);
DISPLAY 0.680851 (-5210 1110);
PAINT MONO (-5210 1110);
FORCEPROP 2 LASTPIN (-4300 900) $PN TH
J 0
(-4290 910);
DISPLAY 0.680851 (-4290 910);
PAINT MONO (-4290 910);
FORCEPROP 2 LASTPIN (-5200 1000) $PN 11
J 2
(-5210 1010);
DISPLAY 0.680851 (-5210 1010);
PAINT MONO (-5210 1010);
FORCEPROP 2 LASTPIN (-5200 1400) $PN 9
J 2
(-5210 1410);
DISPLAY 0.680851 (-5210 1410);
PAINT MONO (-5210 1410);
FORCEPROP 2 LASTPIN (-5200 900) $PN 12
J 2
(-5210 910);
DISPLAY 0.680851 (-5210 910);
PAINT MONO (-5210 910);
FORCEPROP 2 LASTPIN (-5200 950) $PN 13
J 2
(-5210 960);
DISPLAY 0.680851 (-5210 960);
PAINT MONO (-5210 960);
FORCEPROP 2 LAST VALUE ISL28022FRZ-T
J 0
(-5025 1775);
DISPLAY 1.021277 (-5025 1775);
FORCEPROP 2 LAST PART_TYPE SMLF
J 0
(-5025 1825);
DISPLAY 1.021277 (-5025 1825);
FORCEPROP 1 LAST MATERIAL IC
J 0
(-5045 1457);
DISPLAY 0.723404 (-5045 1457);
PAINT GREEN (-5045 1457);
FORCEPROP 2 LAST SEC_TYPE 
J 0
(-5025 1875);
DISPLAY 1.021277 (-5025 1875);
DISPLAY INVISIBLE (-5025 1875);
FORCEPROP 1 LAST CDS_LMAN_SYM_OUTLINE -300,300,300,-300
J 0
(-4750 1150);
DISPLAY 0.468085 (-4750 1150);
PAINT GREEN (-4750 1150);
DISPLAY INVISIBLE (-4750 1150);
FORCEPROP 1 LAST NEEDS_NO_SIZE TRUE
J 0
(-4750 1150);
DISPLAY 0.723404 (-4750 1150);
PAINT GREEN (-4750 1150);
DISPLAY INVISIBLE (-4750 1150);
FORCEPROP 2 LAST CDS_LIB pure_quanta
J 0
(-4750 1150);
DISPLAY INVISIBLE (-4750 1150);
FORCEPROP 1 LAST PATH I57
J 0
(-4750 1150);
DISPLAY 0.723404 (-4750 1150);
PAINT GREEN (-4750 1150);
DISPLAY INVISIBLE (-4750 1150);
FORCEPROP 1 LAST PART_NUMBER AL028022003
J 0
(-5045 1584);
DISPLAY 0.723404 (-5045 1584);
PAINT GREEN (-5045 1584);
DISPLAY INVISIBLE (-5045 1584);
FORCEADD UNIVERSAL_GND..1
(-5500 1550);
FORCEPROP 3 LASTPIN (-5500 1600) SIG_NAME GND\g
J 0
(-5490 1610);
DISPLAY 0.659574 (-5490 1610);
PAINT MONO (-5490 1610);
DISPLAY INVISIBLE (-5490 1610);
FORCEPROP 2 LAST CDS_LIB pure_quanta_power
J 0
(-5500 1550);
DISPLAY INVISIBLE (-5500 1550);
FORCEPROP 1 LAST HDL_POWER GND
J 1
(-5475 1475);
DISPLAY 0.872340 (-5475 1475);
PAINT GREEN (-5475 1475);
DISPLAY INVISIBLE (-5475 1475);
FORCEPROP 1 LAST PATH I58
J 0
(-5425 1550);
DISPLAY 0.872340 (-5425 1550);
PAINT AQUA (-5425 1550);
DISPLAY INVISIBLE (-5425 1550);
FORCEADD OFFPAGE..1
(-7050 5475);
FORCEPROP 2 LAST $XR0 252 
J 0
(-7302 5475);
DISPLAY 0.638298 (-7302 5475);
PAINT MONO (-7302 5475);
FORCEPROP 2 LAST CDS_LIB standard
J 0
(-7050 5475);
DISPLAY INVISIBLE (-7050 5475);
FORCEPROP 1 LAST OFFPAGE TRUE
J 0
(-6725 5350);
DISPLAY 0.872340 (-6725 5350);
DISPLAY INVISIBLE (-6725 5350);
FORCEPROP 1 LAST COMMENT_BODY TRUE
J 0
(-6925 5375);
DISPLAY 0.872340 (-6925 5375);
PAINT GREEN (-6925 5375);
DISPLAY INVISIBLE (-6925 5375);
FORCEPROP 2 LAST PATH I6
J 0
(-7300 5525);
DISPLAY 0.680851 (-7300 5525);
DISPLAY INVISIBLE (-7300 5525);
FORCEADD UNIVERSAL_POWER..1
(-5250 2150);
FORCEPROP 3 LASTPIN (-5250 2100) SIG_NAME P3V3_AUX\g
J 0
(-5240 2110);
DISPLAY 0.659574 (-5240 2110);
PAINT MONO (-5240 2110);
DISPLAY INVISIBLE (-5240 2110);
FORCEPROP 1 LAST HDL_POWER P3V3_AUX
J 1
(-5250 2200);
DISPLAY 0.872340 (-5250 2200);
PAINT GREEN (-5250 2200);
FORCEPROP 2 LAST CDS_LIB pure_quanta_power
J 0
(-5250 2150);
DISPLAY INVISIBLE (-5250 2150);
FORCEPROP 1 LAST PATH I60
J 0
(-5200 2175);
DISPLAY 0.872340 (-5200 2175);
PAINT AQUA (-5200 2175);
DISPLAY INVISIBLE (-5200 2175);
FORCEADD OFFPAGE..2
(-1625 1400);
FORCEPROP 2 LAST $XR1 82 
J 0
(-1316 1400);
DISPLAY 0.638298 (-1316 1400);
PAINT MONO (-1316 1400);
FORCEPROP 2 LAST $XR0 237 
J 0
(-1436 1400);
DISPLAY 0.638298 (-1436 1400);
PAINT MONO (-1436 1400);
FORCEPROP 2 LAST CDS_LIB standard
J 0
(-1625 1400);
DISPLAY INVISIBLE (-1625 1400);
FORCEPROP 1 LAST OFFPAGE TRUE
J 0
(-1300 1275);
DISPLAY 0.872340 (-1300 1275);
DISPLAY INVISIBLE (-1300 1275);
FORCEPROP 1 LAST COMMENT_BODY TRUE
J 0
(-1670 1305);
DISPLAY 0.872340 (-1670 1305);
PAINT GREEN (-1670 1305);
DISPLAY INVISIBLE (-1670 1305);
FORCEPROP 2 LAST PATH I61
J 0
(-1425 1450);
DISPLAY 0.680851 (-1425 1450);
DISPLAY INVISIBLE (-1425 1450);
FORCEADD Q_RES..1
(-3075 1400);
FORCEPROP 1 LAST LOCATION R1269
J 0
(-3250 1400);
DISPLAY 0.510638 (-3250 1400);
FORCEPROP 0 LAST $SEC 1
J 0
(-2775 1450);
DISPLAY 0.680851 (-2775 1450);
PAINT MONO (-2775 1450);
DISPLAY INVISIBLE (-2775 1450);
FORCEPROP 0 LAST CDS_SEC 1
J 0
(-2775 1450);
DISPLAY 1.021277 (-2775 1450);
DISPLAY INVISIBLE (-2775 1450);
FORCEPROP 1 LASTPIN (-3175 1400) $PN 1
J 0
(-3163 1412);
DISPLAY 0.787234 (-3163 1412);
PAINT MONO (-3163 1412);
FORCEPROP 1 LASTPIN (-2975 1400) $PN 2
J 0
(-3013 1412);
DISPLAY 0.787234 (-3013 1412);
PAINT MONO (-3013 1412);
FORCEPROP 1 LAST VALUE 0
J 2
(-2925 1400);
DISPLAY 0.574468 (-2925 1400);
FORCEPROP 1 LAST MATERIAL CHIP
J 0
(-2900 1400);
DISPLAY 0.574468 (-2900 1400);
FORCEPROP 1 LAST PACK_TYPE 0402LF
J 0
(-2775 1400);
DISPLAY 0.574468 (-2775 1400);
FORCEPROP 1 LAST WATTAGE 1/16W
J 2
(-3000 1325);
DISPLAY 0.723404 (-3000 1325);
PAINT SKYBLUE (-3000 1325);
DISPLAY INVISIBLE (-3000 1325);
FORCEPROP 1 LAST TOLERANCE 5%
J 0
(-3275 1325);
DISPLAY 0.723404 (-3275 1325);
PAINT SKYBLUE (-3275 1325);
DISPLAY INVISIBLE (-3275 1325);
FORCEPROP 2 LAST CDS_LIB pure_quanta
J 0
(-3075 1400);
DISPLAY INVISIBLE (-3075 1400);
FORCEPROP 1 LAST PATH I62
J 0
(-3125 1550);
DISPLAY 0.978723 (-3125 1550);
PAINT WHITE (-3125 1550);
DISPLAY INVISIBLE (-3125 1550);
FORCEPROP 1 LAST PART_NUMBER CS00002JB13
J 0
(-3350 1275);
DISPLAY 0.723404 (-3350 1275);
PAINT WHITE (-3350 1275);
DISPLAY INVISIBLE (-3350 1275);
FORCEADD UNIVERSAL_GND..1
(-4175 500);
FORCEPROP 3 LASTPIN (-4175 550) SIG_NAME GND\g
J 0
(-4165 560);
DISPLAY 0.659574 (-4165 560);
PAINT MONO (-4165 560);
DISPLAY INVISIBLE (-4165 560);
FORCEPROP 2 LAST CDS_LIB pure_quanta_power
J 0
(-4175 500);
DISPLAY INVISIBLE (-4175 500);
FORCEPROP 1 LAST HDL_POWER GND
J 1
(-4150 425);
DISPLAY 0.872340 (-4150 425);
PAINT GREEN (-4150 425);
DISPLAY INVISIBLE (-4150 425);
FORCEPROP 1 LAST PATH I64
J 0
(-4100 500);
DISPLAY 0.872340 (-4100 500);
PAINT AQUA (-4100 500);
DISPLAY INVISIBLE (-4100 500);
FORCEADD UNIVERSAL_POWER..1
(-6100 2050);
FORCEPROP 3 LASTPIN (-6100 2000) SIG_NAME P3V3_AUX\g
J 0
(-6090 2010);
DISPLAY 0.659574 (-6090 2010);
PAINT MONO (-6090 2010);
DISPLAY INVISIBLE (-6090 2010);
FORCEPROP 1 LAST HDL_POWER P3V3_AUX
J 1
(-6100 2100);
DISPLAY 0.872340 (-6100 2100);
PAINT GREEN (-6100 2100);
FORCEPROP 2 LAST CDS_LIB pure_quanta_power
J 0
(-6100 2050);
DISPLAY INVISIBLE (-6100 2050);
FORCEPROP 1 LAST PATH I65
J 0
(-6050 2075);
DISPLAY 0.872340 (-6050 2075);
PAINT AQUA (-6050 2075);
DISPLAY INVISIBLE (-6050 2075);
FORCEADD Q_CAP..1
(-5500 1750);
FORCEPROP 1 LAST LOCATION C1096
J 0
(-5450 1850);
DISPLAY 0.978723 (-5450 1850);
FORCEPROP 0 LAST $SEC 1
J 0
(-5450 1900);
DISPLAY 0.680851 (-5450 1900);
PAINT MONO (-5450 1900);
DISPLAY INVISIBLE (-5450 1900);
FORCEPROP 0 LAST CDS_SEC 1
J 0
(-5450 1900);
DISPLAY 1.021277 (-5450 1900);
DISPLAY INVISIBLE (-5450 1900);
FORCEPROP 1 LASTPIN (-5500 1850) $PN 1
J 0
(-5490 1830);
DISPLAY 0.787234 (-5490 1830);
PAINT MONO (-5490 1830);
FORCEPROP 1 LASTPIN (-5500 1650) $PN 2
J 0
(-5490 1630);
DISPLAY 0.787234 (-5490 1630);
PAINT MONO (-5490 1630);
FORCEPROP 1 LAST PACK_TYPE 0402
J 0
(-5450 1600);
DISPLAY 0.638298 (-5450 1600);
FORCEPROP 1 LAST TOLERANCE 10%
J 0
(-5450 1700);
DISPLAY 0.638298 (-5450 1700);
FORCEPROP 1 LAST VALUE 0.1UF
J 0
(-5450 1800);
DISPLAY 0.638298 (-5450 1800);
FORCEPROP 1 LAST VOLTAGE 25V
J 0
(-5450 1750);
DISPLAY 0.638298 (-5450 1750);
FORCEPROP 1 LAST MATERIAL X7R
J 0
(-5450 1650);
DISPLAY 0.638298 (-5450 1650);
FORCEPROP 2 LAST CDS_LIB pure_quanta
J 0
(-5500 1750);
DISPLAY INVISIBLE (-5500 1750);
FORCEPROP 1 LAST PATH I66
J 0
(-5450 1900);
DISPLAY 0.978723 (-5450 1900);
PAINT WHITE (-5450 1900);
DISPLAY INVISIBLE (-5450 1900);
FORCEPROP 1 LAST PART_NUMBER CH4104K1B00
J 0
(-5450 1600);
DISPLAY 0.808511 (-5450 1600);
DISPLAY INVISIBLE (-5450 1600);
FORCEADD Q_CAP..1
(-6025 400);
FORCEPROP 1 LAST LOCATION C1110
J 0
(-5975 500);
DISPLAY 0.978723 (-5975 500);
FORCEPROP 0 LAST $SEC 1
J 0
(-5975 550);
DISPLAY 0.680851 (-5975 550);
PAINT MONO (-5975 550);
DISPLAY INVISIBLE (-5975 550);
FORCEPROP 0 LAST CDS_SEC 1
J 0
(-5975 550);
DISPLAY 1.021277 (-5975 550);
DISPLAY INVISIBLE (-5975 550);
FORCEPROP 1 LASTPIN (-6025 500) $PN 1
J 0
(-6015 480);
DISPLAY 0.787234 (-6015 480);
PAINT MONO (-6015 480);
FORCEPROP 1 LASTPIN (-6025 300) $PN 2
J 0
(-6015 280);
DISPLAY 0.787234 (-6015 280);
PAINT MONO (-6015 280);
FORCEPROP 1 LAST MATERIAL X7R
J 0
(-5975 375);
DISPLAY 0.510638 (-5975 375);
FORCEPROP 1 LAST TOLERANCE 10%
J 0
(-5975 400);
DISPLAY 0.510638 (-5975 400);
FORCEPROP 1 LAST VALUE 0.1UF
J 0
(-5975 450);
DISPLAY 0.510638 (-5975 450);
FORCEPROP 1 LAST VOLTAGE 25V
J 0
(-5975 425);
DISPLAY 0.510638 (-5975 425);
FORCEPROP 1 LAST PACK_TYPE 0402
J 0
(-5975 325);
DISPLAY 0.510638 (-5975 325);
FORCEPROP 2 LAST CDS_LIB pure_quanta
J 0
(-6025 400);
DISPLAY INVISIBLE (-6025 400);
FORCEPROP 1 LAST PATH I68
J 0
(-5975 550);
DISPLAY 0.978723 (-5975 550);
PAINT WHITE (-5975 550);
DISPLAY INVISIBLE (-5975 550);
FORCEPROP 1 LAST PART_NUMBER CH4104K1B00
J 0
(-5975 350);
DISPLAY 0.510638 (-5975 350);
DISPLAY INVISIBLE (-5975 350);
FORCEADD OFFPAGE..3
R 2
(-7050 5425);
FORCEPROP 2 LAST $XR0 252 
J 0
(-7360 5425);
DISPLAY 0.638298 (-7360 5425);
PAINT MONO (-7360 5425);
FORCEPROP 2 LAST CDS_LIB standard
J 2
(-7050 5425);
PAINT MONO (-7050 5425);
DISPLAY INVISIBLE (-7050 5425);
FORCEPROP 1 LAST OFFPAGE TRUE
J 2
(-7375 5300);
DISPLAY 0.872340 (-7375 5300);
DISPLAY INVISIBLE (-7375 5300);
FORCEPROP 1 LAST COMMENT_BODY TRUE
J 2
(-7000 5325);
DISPLAY 0.872340 (-7000 5325);
PAINT GREEN (-7000 5325);
DISPLAY INVISIBLE (-7000 5325);
FORCEPROP 2 LAST PATH I7
J 0
(-7325 5475);
DISPLAY 0.680851 (-7325 5475);
DISPLAY INVISIBLE (-7325 5475);
FORCEADD Q_RES..1
(-6400 1100);
FORCEPROP 1 LAST LOCATION R1275
J 0
(-6675 1100);
DISPLAY 0.787234 (-6675 1100);
FORCEPROP 0 LAST $SEC 1
J 0
(-6100 1150);
DISPLAY 0.680851 (-6100 1150);
PAINT MONO (-6100 1150);
DISPLAY INVISIBLE (-6100 1150);
FORCEPROP 0 LAST CDS_SEC 1
J 0
(-6100 1150);
DISPLAY 0.680851 (-6100 1150);
DISPLAY INVISIBLE (-6100 1150);
FORCEPROP 1 LASTPIN (-6500 1100) $PN 1
J 0
(-6488 1112);
DISPLAY 0.787234 (-6488 1112);
PAINT MONO (-6488 1112);
FORCEPROP 1 LASTPIN (-6300 1100) $PN 2
J 0
(-6338 1112);
DISPLAY 0.787234 (-6338 1112);
PAINT MONO (-6338 1112);
FORCEPROP 1 LAST TOLERANCE 5%
J 0
(-6225 1100);
DISPLAY 0.510638 (-6225 1100);
FORCEPROP 1 LAST VALUE 0
J 2
(-6250 1100);
DISPLAY 0.510638 (-6250 1100);
FORCEPROP 1 LAST MATERIAL CHIP
J 0
(-6175 1100);
DISPLAY 0.510638 (-6175 1100);
FORCEPROP 1 LAST PACK_TYPE 0402LF
J 0
(-6500 1175);
DISPLAY 0.404255 (-6500 1175);
DISPLAY INVISIBLE (-6500 1175);
FORCEPROP 1 LAST WATTAGE 1/16W
J 2
(-6225 1175);
DISPLAY 0.510638 (-6225 1175);
DISPLAY INVISIBLE (-6225 1175);
FORCEPROP 2 LAST CDS_LIB pure_quanta
J 0
(-6400 1100);
DISPLAY INVISIBLE (-6400 1100);
FORCEPROP 1 LAST PATH I70
J 0
(-6450 1250);
DISPLAY 0.978723 (-6450 1250);
PAINT WHITE (-6450 1250);
DISPLAY INVISIBLE (-6450 1250);
FORCEPROP 1 LAST PART_NUMBER CS00002JB13
J 0
(-6500 1150);
DISPLAY 0.404255 (-6500 1150);
DISPLAY INVISIBLE (-6500 1150);
FORCEADD Q_RES..1
(-6400 1150);
FORCEPROP 1 LAST LOCATION R1272
J 0
(-6675 1150);
DISPLAY 0.787234 (-6675 1150);
FORCEPROP 0 LAST $SEC 1
J 0
(-6225 1250);
DISPLAY 0.680851 (-6225 1250);
PAINT MONO (-6225 1250);
DISPLAY INVISIBLE (-6225 1250);
FORCEPROP 0 LAST CDS_SEC 1
J 0
(-6225 1250);
DISPLAY 0.680851 (-6225 1250);
DISPLAY INVISIBLE (-6225 1250);
FORCEPROP 1 LASTPIN (-6500 1150) $PN 1
J 0
(-6488 1162);
DISPLAY 0.787234 (-6488 1162);
PAINT MONO (-6488 1162);
FORCEPROP 1 LASTPIN (-6300 1150) $PN 2
J 0
(-6338 1162);
DISPLAY 0.787234 (-6338 1162);
PAINT MONO (-6338 1162);
FORCEPROP 1 LAST TOLERANCE 5%
J 0
(-6225 1150);
DISPLAY 0.510638 (-6225 1150);
FORCEPROP 1 LAST MATERIAL CHIP
J 0
(-6175 1150);
DISPLAY 0.510638 (-6175 1150);
FORCEPROP 1 LAST VALUE 0
J 2
(-6250 1150);
DISPLAY 0.510638 (-6250 1150);
FORCEPROP 1 LAST WATTAGE 1/16W
J 2
(-6225 1225);
DISPLAY 0.510638 (-6225 1225);
FORCEPROP 1 LAST PACK_TYPE 0402LF
J 0
(-6500 1225);
DISPLAY 0.404255 (-6500 1225);
FORCEPROP 2 LAST CDS_LIB pure_quanta
J 0
(-6400 1150);
DISPLAY INVISIBLE (-6400 1150);
FORCEPROP 1 LAST PATH I71
J 0
(-6450 1300);
DISPLAY 0.978723 (-6450 1300);
PAINT WHITE (-6450 1300);
DISPLAY INVISIBLE (-6450 1300);
FORCEPROP 1 LAST PART_NUMBER CS00002JB13
J 0
(-6500 1200);
DISPLAY 0.404255 (-6500 1200);
DISPLAY INVISIBLE (-6500 1200);
FORCEADD Q_RES..1
(-7200 1475);
FORCEPROP 1 LAST LOCATION R1305
J 0
(-7325 1475);
DISPLAY 0.638298 (-7325 1475);
FORCEPROP 0 LAST $SEC 1
J 0
(-7325 1525);
DISPLAY 0.680851 (-7325 1525);
PAINT MONO (-7325 1525);
DISPLAY INVISIBLE (-7325 1525);
FORCEPROP 0 LAST CDS_SEC 1
J 0
(-7325 1525);
DISPLAY 1.021277 (-7325 1525);
DISPLAY INVISIBLE (-7325 1525);
FORCEPROP 1 LASTPIN (-7300 1475) $PN 1
J 0
(-7288 1487);
DISPLAY 0.787234 (-7288 1487);
PAINT MONO (-7288 1487);
FORCEPROP 1 LASTPIN (-7100 1475) $PN 2
J 0
(-7138 1487);
DISPLAY 0.787234 (-7138 1487);
PAINT MONO (-7138 1487);
FORCEPROP 1 LAST TOLERANCE 1%
J 0
(-6875 1475);
DISPLAY 0.510638 (-6875 1475);
FORCEPROP 1 LAST MATERIAL EMPTY
J 0
(-6825 1475);
DISPLAY 0.510638 (-6825 1475);
PAINT RED (-6825 1475);
FORCEPROP 1 LAST PACK_TYPE 0402LF
J 0
(-6725 1475);
DISPLAY 0.510638 (-6725 1475);
FORCEPROP 1 LAST WATTAGE 1/16W
J 2
(-6875 1475);
DISPLAY 0.510638 (-6875 1475);
FORCEPROP 1 LAST VALUE 4.7K
J 2
(-7000 1475);
DISPLAY 0.510638 (-7000 1475);
FORCEPROP 2 LAST CDS_LIB pure_quanta
J 0
(-7200 1475);
DISPLAY INVISIBLE (-7200 1475);
FORCEPROP 1 LAST PATH I72
J 0
(-7250 1625);
DISPLAY 0.978723 (-7250 1625);
PAINT WHITE (-7250 1625);
DISPLAY INVISIBLE (-7250 1625);
FORCEPROP 1 LAST PART_NUMBER CS24702FB06
J 0
(-7625 1475);
DISPLAY 0.510638 (-7625 1475);
DISPLAY INVISIBLE (-7625 1475);
FORCEADD Q_RES..1
(-6375 550);
FORCEPROP 1 LAST LOCATION R1283
J 0
(-6625 550);
DISPLAY 0.638298 (-6625 550);
FORCEPROP 0 LAST $SEC 1
J 0
(-6525 650);
DISPLAY 0.680851 (-6525 650);
PAINT MONO (-6525 650);
DISPLAY INVISIBLE (-6525 650);
FORCEPROP 0 LAST CDS_SEC 1
J 0
(-6525 650);
DISPLAY 1.021277 (-6525 650);
DISPLAY INVISIBLE (-6525 650);
FORCEPROP 1 LASTPIN (-6475 550) $PN 1
J 0
(-6463 562);
DISPLAY 0.787234 (-6463 562);
PAINT MONO (-6463 562);
FORCEPROP 1 LASTPIN (-6275 550) $PN 2
J 0
(-6313 562);
DISPLAY 0.787234 (-6313 562);
PAINT MONO (-6313 562);
FORCEPROP 1 LAST MATERIAL CHIP
J 0
(-6350 450);
DISPLAY 0.638298 (-6350 450);
FORCEPROP 1 LAST WATTAGE 1/16W
J 2
(-6375 450);
DISPLAY 0.638298 (-6375 450);
FORCEPROP 1 LAST VALUE 10
J 2
(-6425 500);
DISPLAY 0.638298 (-6425 500);
FORCEPROP 1 LAST PACK_TYPE 0402LF
J 0
(-6250 500);
DISPLAY 0.638298 (-6250 500);
FORCEPROP 1 LAST TOLERANCE 1%
J 0
(-6325 500);
DISPLAY 0.638298 (-6325 500);
FORCEPROP 2 LAST CDS_LIB pure_quanta
J 0
(-6375 550);
DISPLAY INVISIBLE (-6375 550);
FORCEPROP 1 LAST PATH I74
J 0
(-6425 700);
DISPLAY 0.978723 (-6425 700);
PAINT WHITE (-6425 700);
DISPLAY INVISIBLE (-6425 700);
FORCEPROP 1 LAST PART_NUMBER CS01002FB07
J 0
(-6525 600);
DISPLAY 0.638298 (-6525 600);
DISPLAY INVISIBLE (-6525 600);
FORCEADD Q_RES..1
(-6375 275);
FORCEPROP 1 LAST LOCATION R1292
J 0
(-6625 275);
DISPLAY 0.638298 (-6625 275);
FORCEPROP 0 LAST $SEC 1
J 0
(-6525 375);
DISPLAY 0.680851 (-6525 375);
PAINT MONO (-6525 375);
DISPLAY INVISIBLE (-6525 375);
FORCEPROP 0 LAST CDS_SEC 1
J 0
(-6525 375);
DISPLAY 1.021277 (-6525 375);
DISPLAY INVISIBLE (-6525 375);
FORCEPROP 1 LASTPIN (-6475 275) $PN 1
J 0
(-6463 287);
DISPLAY 0.787234 (-6463 287);
PAINT MONO (-6463 287);
FORCEPROP 1 LASTPIN (-6275 275) $PN 2
J 0
(-6313 287);
DISPLAY 0.787234 (-6313 287);
PAINT MONO (-6313 287);
FORCEPROP 1 LAST PACK_TYPE 0402LF
J 0
(-6250 225);
DISPLAY 0.638298 (-6250 225);
FORCEPROP 1 LAST VALUE 10
J 2
(-6425 225);
DISPLAY 0.638298 (-6425 225);
FORCEPROP 1 LAST WATTAGE 1/16W
J 2
(-6375 175);
DISPLAY 0.638298 (-6375 175);
FORCEPROP 1 LAST MATERIAL CHIP
J 0
(-6350 175);
DISPLAY 0.638298 (-6350 175);
FORCEPROP 1 LAST TOLERANCE 1%
J 0
(-6325 225);
DISPLAY 0.638298 (-6325 225);
FORCEPROP 2 LAST CDS_LIB pure_quanta
J 0
(-6375 275);
DISPLAY INVISIBLE (-6375 275);
FORCEPROP 1 LAST PATH I75
J 0
(-6425 425);
DISPLAY 0.978723 (-6425 425);
PAINT WHITE (-6425 425);
DISPLAY INVISIBLE (-6425 425);
FORCEPROP 1 LAST PART_NUMBER CS01002FB07
J 0
(-6525 325);
DISPLAY 0.638298 (-6525 325);
DISPLAY INVISIBLE (-6525 325);
FORCEADD UNIVERSAL_GND..1
(-7625 1225);
FORCEPROP 3 LASTPIN (-7625 1275) SIG_NAME GND\g
J 0
(-7615 1285);
DISPLAY 0.659574 (-7615 1285);
PAINT MONO (-7615 1285);
DISPLAY INVISIBLE (-7615 1285);
FORCEPROP 2 LAST CDS_LIB pure_quanta_power
J 0
(-7625 1225);
DISPLAY INVISIBLE (-7625 1225);
FORCEPROP 1 LAST HDL_POWER GND
J 1
(-7600 1150);
DISPLAY 0.872340 (-7600 1150);
PAINT GREEN (-7600 1150);
DISPLAY INVISIBLE (-7600 1150);
FORCEPROP 1 LAST PATH I76
J 0
(-7550 1225);
DISPLAY 0.872340 (-7550 1225);
PAINT AQUA (-7550 1225);
DISPLAY INVISIBLE (-7550 1225);
FORCEADD OFFPAGE..1
(-7600 1150);
FORCEPROP 2 LAST $XR0 252 
J 0
(-7882 1150);
DISPLAY 0.638298 (-7882 1150);
PAINT MONO (-7882 1150);
FORCEPROP 2 LAST CDS_LIB standard
J 0
(-7600 1150);
DISPLAY INVISIBLE (-7600 1150);
FORCEPROP 1 LAST OFFPAGE TRUE
J 0
(-7275 1025);
DISPLAY 0.872340 (-7275 1025);
DISPLAY INVISIBLE (-7275 1025);
FORCEPROP 1 LAST COMMENT_BODY TRUE
J 0
(-7475 1050);
DISPLAY 0.872340 (-7475 1050);
PAINT GREEN (-7475 1050);
DISPLAY INVISIBLE (-7475 1050);
FORCEPROP 2 LAST PATH I77
J 0
(-7850 1200);
DISPLAY 0.680851 (-7850 1200);
DISPLAY INVISIBLE (-7850 1200);
FORCEADD OFFPAGE..3
R 2
(-7600 1100);
FORCEPROP 2 LAST $XR0 252 
J 0
(-7910 1100);
DISPLAY 0.638298 (-7910 1100);
PAINT MONO (-7910 1100);
FORCEPROP 2 LAST CDS_LIB standard
J 2
(-7600 1100);
PAINT MONO (-7600 1100);
DISPLAY INVISIBLE (-7600 1100);
FORCEPROP 1 LAST OFFPAGE TRUE
J 2
(-7925 975);
DISPLAY 0.872340 (-7925 975);
DISPLAY INVISIBLE (-7925 975);
FORCEPROP 1 LAST COMMENT_BODY TRUE
J 2
(-7550 1000);
DISPLAY 0.872340 (-7550 1000);
PAINT GREEN (-7550 1000);
DISPLAY INVISIBLE (-7550 1000);
FORCEPROP 2 LAST PATH I78
J 0
(-7875 1150);
DISPLAY 0.680851 (-7875 1150);
DISPLAY INVISIBLE (-7875 1150);
FORCEADD UNIVERSAL_POWER..1
(-7775 900);
FORCEPROP 3 LASTPIN (-7775 850) SIG_NAME P12V_E1S_0\g
J 0
(-7765 860);
DISPLAY 0.659574 (-7765 860);
PAINT MONO (-7765 860);
DISPLAY INVISIBLE (-7765 860);
FORCEPROP 1 LAST HDL_POWER P12V_E1S_0
J 1
(-7775 950);
DISPLAY 0.872340 (-7775 950);
PAINT GREEN (-7775 950);
FORCEPROP 2 LAST CDS_LIB pure_quanta_power
J 0
(-7775 900);
DISPLAY INVISIBLE (-7775 900);
FORCEPROP 1 LAST PATH I79
J 0
(-7725 925);
DISPLAY 0.872340 (-7725 925);
PAINT AQUA (-7725 925);
DISPLAY INVISIBLE (-7725 925);
FORCEADD UNIVERSAL_GND..1
(-7075 5550);
FORCEPROP 3 LASTPIN (-7075 5600) SIG_NAME GND\g
J 0
(-7065 5610);
DISPLAY 0.659574 (-7065 5610);
PAINT MONO (-7065 5610);
DISPLAY INVISIBLE (-7065 5610);
FORCEPROP 2 LAST CDS_LIB pure_quanta_power
J 0
(-7075 5550);
DISPLAY INVISIBLE (-7075 5550);
FORCEPROP 1 LAST HDL_POWER GND
J 1
(-7050 5475);
DISPLAY 0.872340 (-7050 5475);
PAINT GREEN (-7050 5475);
DISPLAY INVISIBLE (-7050 5475);
FORCEPROP 1 LAST PATH I8
J 0
(-7000 5550);
DISPLAY 0.872340 (-7000 5550);
PAINT AQUA (-7000 5550);
DISPLAY INVISIBLE (-7000 5550);
FORCEADD UNIVERSAL_POWER..1
(-7925 1650);
FORCEPROP 3 LASTPIN (-7925 1600) SIG_NAME P12V_E1S_0\g
J 0
(-7915 1610);
DISPLAY 0.659574 (-7915 1610);
PAINT MONO (-7915 1610);
DISPLAY INVISIBLE (-7915 1610);
FORCEPROP 1 LAST HDL_POWER P12V_E1S_0
J 1
(-7925 1700);
DISPLAY 0.872340 (-7925 1700);
PAINT GREEN (-7925 1700);
FORCEPROP 2 LAST CDS_LIB pure_quanta_power
J 0
(-7925 1650);
DISPLAY INVISIBLE (-7925 1650);
FORCEPROP 1 LAST PATH I80
J 0
(-7875 1675);
DISPLAY 0.872340 (-7875 1675);
PAINT AQUA (-7875 1675);
DISPLAY INVISIBLE (-7875 1675);
FORCEADD Q_CAP..1
(-8175 1325);
FORCEPROP 1 LAST LOCATION C1107
J 0
(-8125 1425);
DISPLAY 0.978723 (-8125 1425);
FORCEPROP 0 LAST $SEC 1
J 0
(-8125 1475);
DISPLAY 0.680851 (-8125 1475);
PAINT MONO (-8125 1475);
DISPLAY INVISIBLE (-8125 1475);
FORCEPROP 0 LAST CDS_SEC 1
J 0
(-8125 1475);
DISPLAY 1.021277 (-8125 1475);
DISPLAY INVISIBLE (-8125 1475);
FORCEPROP 1 LASTPIN (-8175 1425) $PN 1
J 0
(-8165 1405);
DISPLAY 0.787234 (-8165 1405);
PAINT MONO (-8165 1405);
FORCEPROP 1 LASTPIN (-8175 1225) $PN 2
J 0
(-8165 1205);
DISPLAY 0.787234 (-8165 1205);
PAINT MONO (-8165 1205);
FORCEPROP 1 LAST MATERIAL X7R
J 0
(-8125 1225);
DISPLAY 0.638298 (-8125 1225);
FORCEPROP 1 LAST VOLTAGE 25V
J 0
(-8125 1325);
DISPLAY 0.638298 (-8125 1325);
FORCEPROP 1 LAST TOLERANCE 10%
J 0
(-8125 1275);
DISPLAY 0.638298 (-8125 1275);
FORCEPROP 1 LAST PACK_TYPE 0402
J 0
(-8125 1175);
DISPLAY 0.638298 (-8125 1175);
FORCEPROP 1 LAST VALUE 0.1UF
J 0
(-8125 1375);
DISPLAY 0.638298 (-8125 1375);
FORCEPROP 2 LAST CDS_LIB pure_quanta
J 0
(-8175 1325);
DISPLAY INVISIBLE (-8175 1325);
FORCEPROP 1 LAST PATH I81
J 0
(-8125 1475);
DISPLAY 0.978723 (-8125 1475);
PAINT WHITE (-8125 1475);
DISPLAY INVISIBLE (-8125 1475);
FORCEPROP 1 LAST PART_NUMBER CH4104K1B00
J 0
(-8125 1175);
DISPLAY 0.808511 (-8125 1175);
DISPLAY INVISIBLE (-8125 1175);
FORCEADD UNIVERSAL_GND..1
(-8175 1050);
FORCEPROP 3 LASTPIN (-8175 1100) SIG_NAME GND\g
J 0
(-8165 1110);
DISPLAY 0.659574 (-8165 1110);
PAINT MONO (-8165 1110);
DISPLAY INVISIBLE (-8165 1110);
FORCEPROP 2 LAST CDS_LIB pure_quanta_power
J 0
(-8175 1050);
DISPLAY INVISIBLE (-8175 1050);
FORCEPROP 1 LAST HDL_POWER GND
J 1
(-8150 975);
DISPLAY 0.872340 (-8150 975);
PAINT GREEN (-8150 975);
DISPLAY INVISIBLE (-8150 975);
FORCEPROP 1 LAST PATH I82
J 0
(-8100 1050);
DISPLAY 0.872340 (-8100 1050);
PAINT AQUA (-8100 1050);
DISPLAY INVISIBLE (-8100 1050);
FORCEADD UNIVERSAL_POWER..1
(-8850 900);
FORCEPROP 3 LASTPIN (-8850 850) SIG_NAME P12V_E1S_0_R\g
J 0
(-8840 860);
DISPLAY 0.659574 (-8840 860);
PAINT MONO (-8840 860);
DISPLAY INVISIBLE (-8840 860);
FORCEPROP 1 LAST HDL_POWER P12V_E1S_0_R
J 1
(-8850 950);
DISPLAY 0.872340 (-8850 950);
PAINT GREEN (-8850 950);
FORCEPROP 2 LAST CDS_LIB pure_quanta_power
J 0
(-8850 900);
DISPLAY INVISIBLE (-8850 900);
FORCEPROP 1 LAST PATH I83
J 0
(-8800 925);
DISPLAY 0.872340 (-8800 925);
PAINT AQUA (-8800 925);
DISPLAY INVISIBLE (-8800 925);
FORCEADD Q_RES..1
(-8275 750);
FORCEPROP 1 LAST LOCATION R1323
J 0
(-8325 800);
DISPLAY 0.978723 (-8325 800);
FORCEPROP 0 LAST $SEC 1
J 0
(-8325 850);
DISPLAY 0.680851 (-8325 850);
PAINT MONO (-8325 850);
DISPLAY INVISIBLE (-8325 850);
FORCEPROP 0 LAST CDS_SEC 1
J 0
(-8325 850);
DISPLAY 1.021277 (-8325 850);
DISPLAY INVISIBLE (-8325 850);
FORCEPROP 1 LASTPIN (-8375 750) $PN 1
J 0
(-8363 762);
DISPLAY 0.787234 (-8363 762);
PAINT MONO (-8363 762);
FORCEPROP 1 LASTPIN (-8175 750) $PN 2
J 0
(-8213 762);
DISPLAY 0.787234 (-8213 762);
PAINT MONO (-8213 762);
FORCEPROP 1 LAST TOLERANCE 1%
J 0
(-8275 650);
DISPLAY 0.510638 (-8275 650);
FORCEPROP 1 LAST VALUE 0.002
J 2
(-8300 650);
DISPLAY 0.510638 (-8300 650);
FORCEPROP 1 LAST WATTAGE 2W
J 2
(-8300 600);
DISPLAY 0.510638 (-8300 600);
FORCEPROP 1 LAST PACK_TYPE 2512LF
J 0
(-8200 650);
DISPLAY 0.510638 (-8200 650);
FORCEPROP 1 LAST MATERIAL CHIP
J 0
(-8275 600);
DISPLAY 0.510638 (-8275 600);
FORCEPROP 2 LAST CDS_LIB pure_quanta
J 0
(-8275 750);
DISPLAY INVISIBLE (-8275 750);
FORCEPROP 1 LAST PATH I84
J 0
(-8325 900);
DISPLAY 0.978723 (-8325 900);
PAINT WHITE (-8325 900);
DISPLAY INVISIBLE (-8325 900);
FORCEPROP 1 LAST PART_NUMBER CS+002AFR06
J 0
(-8400 700);
DISPLAY 0.510638 (-8400 700);
DISPLAY INVISIBLE (-8400 700);
FORCEADD Q_RES..2
(-2025 6150);
FORCEPROP 1 LAST LOCATION R1327
J 0
(-1980 6275);
DISPLAY 0.978723 (-1980 6275);
FORCEPROP 0 LAST $SEC 1
J 0
(-1975 6325);
DISPLAY 0.680851 (-1975 6325);
PAINT MONO (-1975 6325);
DISPLAY INVISIBLE (-1975 6325);
FORCEPROP 0 LAST CDS_SEC 1
J 0
(-1975 6325);
DISPLAY 0.680851 (-1975 6325);
DISPLAY INVISIBLE (-1975 6325);
FORCEPROP 1 LASTPIN (-2025 6250) $PN 1
J 0
(-2020 6212);
DISPLAY 0.787234 (-2020 6212);
PAINT MONO (-2020 6212);
FORCEPROP 1 LASTPIN (-2025 6050) $PN 2
J 0
(-2020 6060);
DISPLAY 0.787234 (-2020 6060);
PAINT MONO (-2020 6060);
FORCEPROP 1 LAST WATTAGE 1/16W
J 0
(-1985 6125);
DISPLAY 0.978723 (-1985 6125);
FORCEPROP 1 LAST MATERIAL EMPTY
J 0
(-1985 6075);
DISPLAY 0.978723 (-1985 6075);
FORCEPROP 1 LAST PACK_TYPE 0402LF
J 0
(-1985 5975);
DISPLAY 0.978723 (-1985 5975);
FORCEPROP 1 LAST VALUE 1K
J 0
(-1980 6225);
DISPLAY 0.978723 (-1980 6225);
FORCEPROP 1 LAST TOLERANCE 1%
J 0
(-1980 6175);
DISPLAY 0.978723 (-1980 6175);
FORCEPROP 2 LAST CDS_LIB pure_quanta
J 0
(-2025 6150);
DISPLAY INVISIBLE (-2025 6150);
FORCEPROP 1 LAST PATH I85
J 0
(-1975 6325);
DISPLAY 0.978723 (-1975 6325);
PAINT WHITE (-1975 6325);
DISPLAY INVISIBLE (-1975 6325);
FORCEPROP 1 LAST PART_NUMBER CS21002FB06
J 0
(-1985 6025);
DISPLAY 0.978723 (-1985 6025);
DISPLAY INVISIBLE (-1985 6025);
FORCEADD UNIVERSAL_POWER..1
(-2025 6400);
FORCEPROP 3 LASTPIN (-2025 6350) SIG_NAME P3V3_AUX\g
J 0
(-2015 6360);
DISPLAY 0.659574 (-2015 6360);
PAINT MONO (-2015 6360);
DISPLAY INVISIBLE (-2015 6360);
FORCEPROP 1 LAST HDL_POWER P3V3_AUX
J 1
(-2025 6450);
DISPLAY 0.872340 (-2025 6450);
PAINT GREEN (-2025 6450);
FORCEPROP 2 LAST CDS_LIB pure_quanta_power
J 0
(-2025 6400);
DISPLAY INVISIBLE (-2025 6400);
FORCEPROP 1 LAST PATH I86
J 0
(-1975 6425);
DISPLAY 0.872340 (-1975 6425);
PAINT AQUA (-1975 6425);
DISPLAY INVISIBLE (-1975 6425);
FORCEADD Q_RES..2
(-1400 4100);
FORCEPROP 1 LAST LOCATION R1328
J 0
(-1355 4225);
DISPLAY 0.978723 (-1355 4225);
FORCEPROP 0 LAST $SEC 1
J 0
(-1350 4275);
DISPLAY 0.680851 (-1350 4275);
PAINT MONO (-1350 4275);
DISPLAY INVISIBLE (-1350 4275);
FORCEPROP 0 LAST CDS_SEC 1
J 0
(-1350 4275);
DISPLAY 0.680851 (-1350 4275);
DISPLAY INVISIBLE (-1350 4275);
FORCEPROP 1 LASTPIN (-1400 4200) $PN 1
J 0
(-1395 4162);
DISPLAY 0.787234 (-1395 4162);
PAINT MONO (-1395 4162);
FORCEPROP 1 LASTPIN (-1400 4000) $PN 2
J 0
(-1395 4010);
DISPLAY 0.787234 (-1395 4010);
PAINT MONO (-1395 4010);
FORCEPROP 1 LAST MATERIAL EMPTY
J 0
(-1360 4025);
DISPLAY 0.978723 (-1360 4025);
FORCEPROP 1 LAST PACK_TYPE 0402LF
J 0
(-1360 3925);
DISPLAY 0.978723 (-1360 3925);
FORCEPROP 1 LAST WATTAGE 1/16W
J 0
(-1360 4075);
DISPLAY 0.978723 (-1360 4075);
FORCEPROP 1 LAST TOLERANCE 1%
J 0
(-1355 4125);
DISPLAY 0.978723 (-1355 4125);
FORCEPROP 1 LAST VALUE 1K
J 0
(-1355 4175);
DISPLAY 0.978723 (-1355 4175);
FORCEPROP 2 LAST CDS_LIB pure_quanta
J 0
(-1400 4100);
DISPLAY INVISIBLE (-1400 4100);
FORCEPROP 1 LAST PATH I87
J 0
(-1350 4275);
DISPLAY 0.978723 (-1350 4275);
PAINT WHITE (-1350 4275);
DISPLAY INVISIBLE (-1350 4275);
FORCEPROP 1 LAST PART_NUMBER CS21002FB06
J 0
(-1360 3975);
DISPLAY 0.978723 (-1360 3975);
DISPLAY INVISIBLE (-1360 3975);
FORCEADD UNIVERSAL_POWER..1
(-1400 4350);
FORCEPROP 3 LASTPIN (-1400 4300) SIG_NAME P3V3_AUX\g
J 0
(-1390 4310);
DISPLAY 0.659574 (-1390 4310);
PAINT MONO (-1390 4310);
DISPLAY INVISIBLE (-1390 4310);
FORCEPROP 1 LAST HDL_POWER P3V3_AUX
J 1
(-1400 4400);
DISPLAY 0.872340 (-1400 4400);
PAINT GREEN (-1400 4400);
FORCEPROP 2 LAST CDS_LIB pure_quanta_power
J 0
(-1400 4350);
DISPLAY INVISIBLE (-1400 4350);
FORCEPROP 1 LAST PATH I88
J 0
(-1350 4375);
DISPLAY 0.872340 (-1350 4375);
PAINT AQUA (-1350 4375);
DISPLAY INVISIBLE (-1350 4375);
FORCEADD UNIVERSAL_POWER..1
(-2575 2050);
FORCEPROP 3 LASTPIN (-2575 2000) SIG_NAME P3V3_AUX\g
J 0
(-2565 2010);
DISPLAY 0.659574 (-2565 2010);
PAINT MONO (-2565 2010);
DISPLAY INVISIBLE (-2565 2010);
FORCEPROP 1 LAST HDL_POWER P3V3_AUX
J 1
(-2575 2100);
DISPLAY 0.872340 (-2575 2100);
PAINT GREEN (-2575 2100);
FORCEPROP 2 LAST CDS_LIB pure_quanta_power
J 0
(-2575 2050);
DISPLAY INVISIBLE (-2575 2050);
FORCEPROP 1 LAST PATH I89
J 0
(-2525 2075);
DISPLAY 0.872340 (-2525 2075);
PAINT AQUA (-2525 2075);
DISPLAY INVISIBLE (-2525 2075);
FORCEADD UNIVERSAL_POWER..1
(-7375 5975);
FORCEPROP 3 LASTPIN (-7375 5925) SIG_NAME P12V_OCP_SFF\g
J 0
(-7365 5935);
DISPLAY 0.659574 (-7365 5935);
PAINT MONO (-7365 5935);
DISPLAY INVISIBLE (-7365 5935);
FORCEPROP 1 LAST HDL_POWER P12V_OCP_SFF
J 1
(-7375 6025);
DISPLAY 0.872340 (-7375 6025);
PAINT GREEN (-7375 6025);
FORCEPROP 2 LAST CDS_LIB pure_quanta_power
J 0
(-7375 5975);
DISPLAY INVISIBLE (-7375 5975);
FORCEPROP 1 LAST PATH I9
J 0
(-7325 6000);
DISPLAY 0.872340 (-7325 6000);
PAINT AQUA (-7325 6000);
DISPLAY INVISIBLE (-7325 6000);
FORCEADD Q_RES..2
(-2575 1800);
FORCEPROP 1 LAST LOCATION R1326
J 0
(-2530 1925);
DISPLAY 0.978723 (-2530 1925);
FORCEPROP 0 LAST $SEC 1
J 0
(-2525 1975);
DISPLAY 0.680851 (-2525 1975);
PAINT MONO (-2525 1975);
DISPLAY INVISIBLE (-2525 1975);
FORCEPROP 0 LAST CDS_SEC 1
J 0
(-2525 1975);
DISPLAY 0.680851 (-2525 1975);
DISPLAY INVISIBLE (-2525 1975);
FORCEPROP 1 LASTPIN (-2575 1900) $PN 1
J 0
(-2570 1862);
DISPLAY 0.787234 (-2570 1862);
PAINT MONO (-2570 1862);
FORCEPROP 1 LASTPIN (-2575 1700) $PN 2
J 0
(-2570 1710);
DISPLAY 0.787234 (-2570 1710);
PAINT MONO (-2570 1710);
FORCEPROP 1 LAST VALUE 1K
J 0
(-2530 1875);
DISPLAY 0.978723 (-2530 1875);
FORCEPROP 1 LAST TOLERANCE 1%
J 0
(-2530 1825);
DISPLAY 0.978723 (-2530 1825);
FORCEPROP 1 LAST WATTAGE 1/16W
J 0
(-2535 1775);
DISPLAY 0.978723 (-2535 1775);
FORCEPROP 1 LAST MATERIAL EMPTY
J 0
(-2535 1725);
DISPLAY 0.978723 (-2535 1725);
FORCEPROP 1 LAST PACK_TYPE 0402LF
J 0
(-2535 1625);
DISPLAY 0.978723 (-2535 1625);
FORCEPROP 2 LAST CDS_LIB pure_quanta
J 0
(-2575 1800);
DISPLAY INVISIBLE (-2575 1800);
FORCEPROP 1 LAST PATH I90
J 0
(-2525 1975);
DISPLAY 0.978723 (-2525 1975);
PAINT WHITE (-2525 1975);
DISPLAY INVISIBLE (-2525 1975);
FORCEPROP 1 LAST PART_NUMBER CS21002FB06
J 0
(-2535 1675);
DISPLAY 0.978723 (-2535 1675);
DISPLAY INVISIBLE (-2535 1675);
FORCEADD Q_RES..2
(-5475 5600);
FORCEPROP 1 LAST LOCATION R1355
J 0
(-5400 5675);
DISPLAY 0.638298 (-5400 5675);
FORCEPROP 0 LAST $SEC 1
J 0
(-5400 5725);
DISPLAY 0.680851 (-5400 5725);
PAINT MONO (-5400 5725);
DISPLAY INVISIBLE (-5400 5725);
FORCEPROP 0 LAST CDS_SEC 1
J 0
(-5400 5725);
DISPLAY 0.680851 (-5400 5725);
DISPLAY INVISIBLE (-5400 5725);
FORCEPROP 1 LASTPIN (-5475 5700) $PN 1
J 0
(-5470 5662);
DISPLAY 0.787234 (-5470 5662);
PAINT MONO (-5470 5662);
FORCEPROP 1 LASTPIN (-5475 5500) $PN 2
J 0
(-5470 5510);
DISPLAY 0.787234 (-5470 5510);
PAINT MONO (-5470 5510);
FORCEPROP 1 LAST MATERIAL CHIP
J 0
(-5400 5575);
DISPLAY 0.404255 (-5400 5575);
FORCEPROP 1 LAST VALUE 0
J 0
(-5400 5650);
DISPLAY 0.404255 (-5400 5650);
FORCEPROP 1 LAST TOLERANCE 5%
J 0
(-5400 5625);
DISPLAY 0.404255 (-5400 5625);
FORCEPROP 1 LAST WATTAGE 1/16W
J 0
(-5400 5600);
DISPLAY 0.404255 (-5400 5600);
FORCEPROP 1 LAST PACK_TYPE 0402LF
J 0
(-5400 5550);
DISPLAY 0.404255 (-5400 5550);
FORCEPROP 2 LAST CDS_LIB pure_quanta
J 0
(-5475 5600);
DISPLAY INVISIBLE (-5475 5600);
FORCEPROP 1 LAST PATH I92
J 0
(-5425 5775);
DISPLAY 0.978723 (-5425 5775);
PAINT WHITE (-5425 5775);
DISPLAY INVISIBLE (-5425 5775);
FORCEPROP 1 LAST PART_NUMBER CS00002JB13
J 0
(-5400 5550);
DISPLAY 0.404255 (-5400 5550);
DISPLAY INVISIBLE (-5400 5550);
FORCEADD Q_RES..2
(-4825 3550);
FORCEPROP 1 LAST LOCATION R1360
J 0
(-4750 3625);
DISPLAY 0.510638 (-4750 3625);
FORCEPROP 0 LAST $SEC 1
J 0
(-4750 3650);
DISPLAY 0.680851 (-4750 3650);
PAINT MONO (-4750 3650);
DISPLAY INVISIBLE (-4750 3650);
FORCEPROP 0 LAST CDS_SEC 1
J 0
(-4750 3650);
DISPLAY 0.680851 (-4750 3650);
DISPLAY INVISIBLE (-4750 3650);
FORCEPROP 1 LASTPIN (-4825 3650) $PN 1
J 0
(-4820 3612);
DISPLAY 0.787234 (-4820 3612);
PAINT MONO (-4820 3612);
FORCEPROP 1 LASTPIN (-4825 3450) $PN 2
J 0
(-4820 3460);
DISPLAY 0.787234 (-4820 3460);
PAINT MONO (-4820 3460);
FORCEPROP 1 LAST PACK_TYPE 0402LF
J 0
(-4750 3500);
DISPLAY 0.404255 (-4750 3500);
FORCEPROP 1 LAST WATTAGE 1/16W
J 0
(-4750 3550);
DISPLAY 0.404255 (-4750 3550);
FORCEPROP 1 LAST MATERIAL CHIP
J 0
(-4750 3525);
DISPLAY 0.404255 (-4750 3525);
FORCEPROP 1 LAST TOLERANCE 5%
J 0
(-4750 3575);
DISPLAY 0.404255 (-4750 3575);
FORCEPROP 1 LAST VALUE 0
J 0
(-4750 3600);
DISPLAY 0.404255 (-4750 3600);
FORCEPROP 2 LAST CDS_LIB pure_quanta
J 0
(-4825 3550);
DISPLAY INVISIBLE (-4825 3550);
FORCEPROP 1 LAST PATH I93
J 0
(-4775 3725);
DISPLAY 0.978723 (-4775 3725);
PAINT WHITE (-4775 3725);
DISPLAY INVISIBLE (-4775 3725);
FORCEPROP 1 LAST PART_NUMBER CS00002JB13
J 0
(-4750 3500);
DISPLAY 0.404255 (-4750 3500);
DISPLAY INVISIBLE (-4750 3500);
FORCEADD Q_RES..2
(-6025 1300);
FORCEPROP 1 LAST LOCATION R1350
J 0
(-5950 1375);
DISPLAY 0.510638 (-5950 1375);
FORCEPROP 0 LAST $SEC 1
J 0
(-5950 1400);
DISPLAY 0.680851 (-5950 1400);
PAINT MONO (-5950 1400);
DISPLAY INVISIBLE (-5950 1400);
FORCEPROP 0 LAST CDS_SEC 1
J 0
(-5950 1400);
DISPLAY 0.680851 (-5950 1400);
DISPLAY INVISIBLE (-5950 1400);
FORCEPROP 1 LASTPIN (-6025 1400) $PN 1
J 0
(-6020 1362);
DISPLAY 0.787234 (-6020 1362);
PAINT MONO (-6020 1362);
FORCEPROP 1 LASTPIN (-6025 1200) $PN 2
J 0
(-6020 1210);
DISPLAY 0.787234 (-6020 1210);
PAINT MONO (-6020 1210);
FORCEPROP 1 LAST WATTAGE 1/16W
J 0
(-5950 1300);
DISPLAY 0.404255 (-5950 1300);
FORCEPROP 1 LAST PACK_TYPE 0402LF
J 0
(-5950 1250);
DISPLAY 0.404255 (-5950 1250);
FORCEPROP 1 LAST MATERIAL CHIP
J 0
(-5950 1275);
DISPLAY 0.404255 (-5950 1275);
FORCEPROP 1 LAST TOLERANCE 5%
J 0
(-5950 1325);
DISPLAY 0.404255 (-5950 1325);
FORCEPROP 1 LAST VALUE 0
J 0
(-5950 1350);
DISPLAY 0.404255 (-5950 1350);
FORCEPROP 2 LAST CDS_LIB pure_quanta
J 0
(-6025 1300);
DISPLAY INVISIBLE (-6025 1300);
FORCEPROP 1 LAST PATH I94
J 0
(-5975 1475);
DISPLAY 0.978723 (-5975 1475);
PAINT WHITE (-5975 1475);
DISPLAY INVISIBLE (-5975 1475);
FORCEPROP 1 LAST PART_NUMBER CS00002JB13
J 0
(-5950 1250);
DISPLAY 0.404255 (-5950 1250);
DISPLAY INVISIBLE (-5950 1250);
FORCEADD Q_RES..2
(-6100 1750);
FORCEPROP 1 LAST LOCATION R1317
J 0
(-6055 1875);
DISPLAY 0.638298 (-6055 1875);
FORCEPROP 0 LAST $SEC 1
J 0
(-6050 1925);
DISPLAY 0.680851 (-6050 1925);
PAINT MONO (-6050 1925);
DISPLAY INVISIBLE (-6050 1925);
FORCEPROP 0 LAST CDS_SEC 1
J 0
(-6050 1925);
DISPLAY 0.680851 (-6050 1925);
DISPLAY INVISIBLE (-6050 1925);
FORCEPROP 1 LASTPIN (-6100 1850) $PN 1
J 0
(-6095 1812);
DISPLAY 0.787234 (-6095 1812);
PAINT MONO (-6095 1812);
FORCEPROP 1 LASTPIN (-6100 1650) $PN 2
J 0
(-6095 1660);
DISPLAY 0.787234 (-6095 1660);
PAINT MONO (-6095 1660);
FORCEPROP 1 LAST TOLERANCE 1%
J 0
(-6055 1775);
DISPLAY 0.510638 (-6055 1775);
FORCEPROP 1 LAST MATERIAL EMPTY
J 0
(-6060 1675);
DISPLAY 0.510638 (-6060 1675);
FORCEPROP 1 LAST WATTAGE 1/16W
J 0
(-6060 1725);
DISPLAY 0.510638 (-6060 1725);
FORCEPROP 1 LAST VALUE 4.7K
J 0
(-6055 1825);
DISPLAY 0.510638 (-6055 1825);
FORCEPROP 1 LAST PACK_TYPE 0402LF
J 0
(-6060 1575);
DISPLAY 0.510638 (-6060 1575);
FORCEPROP 2 LAST CDS_LIB pure_quanta
J 0
(-6100 1750);
DISPLAY INVISIBLE (-6100 1750);
FORCEPROP 1 LAST PATH I95
J 0
(-6050 1925);
DISPLAY 0.978723 (-6050 1925);
PAINT WHITE (-6050 1925);
DISPLAY INVISIBLE (-6050 1925);
FORCEPROP 1 LAST PART_NUMBER CS24702FB06
J 0
(-6060 1625);
DISPLAY 0.510638 (-6060 1625);
DISPLAY INVISIBLE (-6060 1625);
FORCEADD Q_RES..1
(-7200 1425);
FORCEPROP 1 LAST LOCATION R1308
J 0
(-7400 1425);
DISPLAY 0.510638 (-7400 1425);
FORCEPROP 0 LAST $SEC 1
J 0
(-6875 1450);
DISPLAY 0.680851 (-6875 1450);
PAINT MONO (-6875 1450);
DISPLAY INVISIBLE (-6875 1450);
FORCEPROP 0 LAST CDS_SEC 1
J 0
(-6875 1450);
DISPLAY 0.680851 (-6875 1450);
DISPLAY INVISIBLE (-6875 1450);
FORCEPROP 1 LASTPIN (-7300 1425) $PN 1
J 0
(-7288 1437);
DISPLAY 0.787234 (-7288 1437);
PAINT MONO (-7288 1437);
FORCEPROP 1 LASTPIN (-7100 1425) $PN 2
J 0
(-7138 1437);
DISPLAY 0.787234 (-7138 1437);
PAINT MONO (-7138 1437);
FORCEPROP 1 LAST PACK_TYPE 0402LF
J 0
(-6875 1425);
DISPLAY 0.510638 (-6875 1425);
FORCEPROP 1 LAST VALUE 4.7K
J 2
(-7000 1425);
DISPLAY 0.510638 (-7000 1425);
FORCEPROP 1 LAST MATERIAL CHIP
J 0
(-6975 1425);
DISPLAY 0.510638 (-6975 1425);
FORCEPROP 2 LAST CDS_LIB pure_quanta
J 0
(-7200 1425);
DISPLAY INVISIBLE (-7200 1425);
FORCEPROP 1 LAST WATTAGE 1/16W
J 2
(-6875 1425);
DISPLAY 0.510638 (-6875 1425);
DISPLAY INVISIBLE (-6875 1425);
FORCEPROP 1 LAST TOLERANCE 1%
J 0
(-7200 1325);
DISPLAY 0.510638 (-7200 1325);
DISPLAY INVISIBLE (-7200 1325);
FORCEPROP 1 LAST PATH I96
J 0
(-7250 1575);
DISPLAY 0.978723 (-7250 1575);
PAINT WHITE (-7250 1575);
DISPLAY INVISIBLE (-7250 1575);
FORCEPROP 1 LAST PART_NUMBER CS24702FB06
J 0
(-7250 1525);
DISPLAY 0.510638 (-7250 1525);
DISPLAY INVISIBLE (-7250 1525);
FORCEADD DNS..2
(-7200 1525);
PAINT RED (-7200 1525);
FORCEPROP 2 LAST CDS_LIB mstr_misc
J 0
(-7200 1525);
DISPLAY INVISIBLE (-7200 1525);
FORCEPROP 1 LAST COMMENT_BODY TRUE
R 1
J 0
(-7125 1300);
DISPLAY 0.872340 (-7125 1300);
PAINT GREEN (-7125 1300);
DISPLAY INVISIBLE (-7125 1300);
FORCEADD DNS..2
(-5975 3675);
PAINT RED (-5975 3675);
FORCEPROP 2 LAST CDS_LIB mstr_misc
J 0
(-5975 3675);
DISPLAY INVISIBLE (-5975 3675);
FORCEPROP 1 LAST COMMENT_BODY TRUE
R 1
J 0
(-5900 3450);
DISPLAY 0.872340 (-5900 3450);
PAINT GREEN (-5900 3450);
DISPLAY INVISIBLE (-5900 3450);
FORCEADD DNS..2
(-5975 3750);
PAINT RED (-5975 3750);
FORCEPROP 2 LAST CDS_LIB mstr_misc
J 0
(-5975 3750);
DISPLAY INVISIBLE (-5975 3750);
FORCEPROP 1 LAST COMMENT_BODY TRUE
R 1
J 0
(-5900 3525);
DISPLAY 0.872340 (-5900 3525);
PAINT GREEN (-5900 3525);
DISPLAY INVISIBLE (-5900 3525);
FORCEADD DNS..2
(-6650 5700);
PAINT RED (-6650 5700);
FORCEPROP 2 LAST CDS_LIB mstr_misc
J 0
(-6650 5700);
DISPLAY INVISIBLE (-6650 5700);
FORCEPROP 1 LAST COMMENT_BODY TRUE
R 1
J 0
(-6575 5475);
DISPLAY 0.872340 (-6575 5475);
PAINT GREEN (-6575 5475);
DISPLAY INVISIBLE (-6575 5475);
FORCEADD DNS..2
(-6625 5800);
PAINT RED (-6625 5800);
FORCEPROP 2 LAST CDS_LIB mstr_misc
J 0
(-6625 5800);
DISPLAY INVISIBLE (-6625 5800);
FORCEPROP 1 LAST COMMENT_BODY TRUE
R 1
J 0
(-6550 5575);
DISPLAY 0.872340 (-6550 5575);
PAINT GREEN (-6550 5575);
DISPLAY INVISIBLE (-6550 5575);
FORCEADD DNS..2
(-1300 4075);
PAINT RED (-1300 4075);
FORCEPROP 2 LAST CDS_LIB mstr_misc
J 0
(-1300 4075);
DISPLAY INVISIBLE (-1300 4075);
FORCEPROP 1 LAST COMMENT_BODY TRUE
R 1
J 0
(-1225 3850);
DISPLAY 0.872340 (-1225 3850);
PAINT GREEN (-1225 3850);
DISPLAY INVISIBLE (-1225 3850);
FORCEADD DNS..2
(-2475 1775);
PAINT RED (-2475 1775);
FORCEPROP 2 LAST CDS_LIB mstr_misc
J 0
(-2475 1775);
DISPLAY INVISIBLE (-2475 1775);
FORCEPROP 1 LAST COMMENT_BODY TRUE
R 1
J 0
(-2400 1550);
DISPLAY 0.872340 (-2400 1550);
PAINT GREEN (-2400 1550);
DISPLAY INVISIBLE (-2400 1550);
FORCEADD QUANTA_TITLE_BLOCK_C..1
(0 0);
FORCEPROP 0 LAST CDS_CON_LAST_MODIFIED Thu Sep 14 16:13:11 2023
J 0
(-1885 15);
DISPLAY INVISIBLE (-1885 15);
FORCEPROP 1 LAST CUSTOM_TXT_CDS <CON_LAST_MODIFIED>
J 0
(-1885 15);
DISPLAY 0.978723 (-1885 15);
FORCEPROP 2 LAST CUSTOM_TXT_CDS <XR_PAGE_TITLE>
J 0
(-7890 5250);
DISPLAY 0.638298 (-7890 5250);
PAINT PINK (-7890 5250);
DISPLAY INVISIBLE (-7890 5250);
FORCEPROP 1 LAST CUSTOM_TXT_CDS <NAME_2>
J 0
(-3175 50);
FORCEPROP 1 LAST CUSTOM_TXT_CDS <NAME_1>
J 0
(-3175 175);
FORCEPROP 1 LAST CUSTOM_TXT_CDS <Q_NUMBER>
J 0
(-1403 103);
DISPLAY 1.212766 (-1403 103);
FORCEPROP 1 LAST CUSTOM_TXT_CDS <Q_PROJ>
J 0
(-2382 102);
DISPLAY 1.212766 (-2382 102);
FORCEPROP 1 LAST CUSTOM_TXT_CDS <Q_REV>
J 0
(-184 103);
DISPLAY 1.212766 (-184 103);
FORCEPROP 1 LAST CUSTOM_TXT_CDS <CON_PAGE_NUM> OF <CON_TOTAL_PAGES>
J 0
(-446 18);
DISPLAY 0.978723 (-446 18);
FORCEPROP 1 LAST Q_TITLE POWER MONITOR (4/4)
J 0
(-9366 26);
DISPLAY 2.446809 (-9366 26);
PAINT GREEN (-9366 26);
FORCEPROP 2 LAST PAGE_BORDER TRUE
J 0
(-7890 5250);
DISPLAY 0.638298 (-7890 5250);
PAINT PINK (-7890 5250);
DISPLAY INVISIBLE (-7890 5250);
FORCEPROP 1 LAST CDS_LMAN_SYM_OUTLINE -9475,6775,100,-125
J 0
(0 0);
DISPLAY 0.468085 (0 0);
PAINT GREEN (0 0);
DISPLAY INVISIBLE (0 0);
FORCEPROP 2 LAST CDS_LIB pure_quanta
J 0
(0 0);
DISPLAY INVISIBLE (0 0);
FORCEPROP 2 LAST CDS_XR_PAGE_TITLE CR-358 : @T6G_MB_LIB.T6G(SCH_1):PAGE358
J 0
(-7890 5250);
DISPLAY 0.638298 (-7890 5250);
PAINT PINK (-7890 5250);
DISPLAY INVISIBLE (-7890 5250);
FORCEPROP 1 LAST Q_DEPT BU9
J 1
(-3763 49);
DISPLAY 1.957447 (-3763 49);
PAINT GREEN (-3763 49);
DISPLAY INVISIBLE (-3763 49);
FORCEPROP 1 LAST COMMENT_BODY TRUE
J 0
(12 -13);
DISPLAY 0.978723 (12 -13);
PAINT GREEN (12 -13);
DISPLAY INVISIBLE (12 -13);
FORCEADD DNS..2
(-1925 6125);
PAINT RED (-1925 6125);
FORCEPROP 2 LAST CDS_LIB mstr_misc
J 0
(-1925 6125);
DISPLAY INVISIBLE (-1925 6125);
FORCEPROP 1 LAST COMMENT_BODY TRUE
R 1
J 0
(-1850 5900);
DISPLAY 0.872340 (-1850 5900);
PAINT GREEN (-1850 5900);
DISPLAY INVISIBLE (-1850 5900);
FORCEADD DNS..2
(-6025 1725);
PAINT RED (-6025 1725);
FORCEPROP 2 LAST CDS_LIB mstr_misc
J 0
(-6025 1725);
DISPLAY INVISIBLE (-6025 1725);
FORCEPROP 1 LAST COMMENT_BODY TRUE
R 1
J 0
(-5950 1500);
DISPLAY 0.872340 (-5950 1500);
PAINT GREEN (-5950 1500);
DISPLAY INVISIBLE (-5950 1500);
FORCEADD BOM_NOTE..1
(-8850 4375);
FORCEPROP 0 LAST S1 POWER MONITOR WILL CHANGE TO AL000230001
J 0
(-9000 4225);
DISPLAY 1.595745 (-9000 4225);
PAINT SKYBLUE (-9000 4225);
FORCEPROP 2 LAST CDS_LIB pure_quanta_power
J 0
(-8850 4375);
DISPLAY INVISIBLE (-8850 4375);
FORCEPROP 1 LAST COMMENT_BODY TRUE
J 0
(-8825 4475);
DISPLAY 0.978723 (-8825 4475);
DISPLAY INVISIBLE (-8825 4475);
WIRE 16 -1 (-4950 5975)(-4950 5900);
WIRE 16 -1 (-5550 6175)(-5550 6325);
WIRE 16 -1 (-4300 3925)(-4300 3850);
WIRE 16 -1 (-4900 4125)(-4900 4275);
WIRE 16 -1 (-7625 5550)(-7625 5425);
WIRE 16 -1 (-6975 3500)(-6975 3375);
WIRE 16 -1 (-5500 1650)(-5500 1600);
WIRE 16 -1 (-6100 1850)(-6100 2000);
WIRE 16 -1 (-8175 1225)(-8175 1100);
WIRE 16 -1 (-2025 6250)(-2025 6350);
WIRE 16 -1 (-1400 4200)(-1400 4300);
WIRE 16 -1 (-2575 1900)(-2575 2000);
WIRE 16 -1 (-7825 5075)(-8000 5075);
WIRE 16 -1 (-8000 5075)(-8000 4600);
WIRE 16 -1 (-8000 5075)(-8300 5075);
WIRE 16 -1 (-8300 5075)(-8300 5175);
WIRE 16 -1 (-8000 4600)(-5925 4600);
WIRE 16 -1 (-4650 5325)(-7375 5325);
WIRE 16 -1 (-7375 5875)(-7375 5325);
WIRE 16 -1 (-7375 5925)(-7375 5875);
WIRE 16 -1 (-7625 5875)(-7375 5875);
WIRE 16 -1 (-7625 5750)(-7625 5875);
WIRE 16 -1 (-7400 4875)(-5925 4875);
WIRE 16 -1 (-7400 4875)(-7400 5075);
WIRE 16 -1 (-7400 5075)(-7625 5075);
WIRE 16 -1 (-7225 5075)(-7400 5075);
WIRE 16 -1 (-7225 5075)(-7225 5175);
WIRE 16 -1 (-2625 5725)(-3750 5725);
FORCEPROP 2 LAST SIG_NAME P12V_OCP_SFF_ADC_ALERT_R
J 0
(-3610 5735);
DISPLAY 0.638298 (-3610 5735);
FORCEPROP 2 LASTPROP $XRERR UNIQUE?
J 0
(-3850 5735);
DISPLAY 0.638298 (-3850 5735);
PAINT MONO (-3850 5735);
DISPLAY INVISIBLE (-3850 5735);
WIRE 16 -1 (-3100 3325)(-2475 3325);
FORCEPROP 2 LAST SIG_NAME NC_INA230_7_NC5
J 0
(-2960 3335);
DISPLAY 0.638298 (-2960 3335);
PAINT SKYBLUE (-2960 3335);
FORCEPROP 2 LASTPROP $XRERR UNIQUE?
J 0
(-2445 3325);
DISPLAY 0.638298 (-2445 3325);
PAINT MONO (-2445 3325);
DISPLAY INVISIBLE (-2445 3325);
WIRE 16 -1 (-2575 1700)(-2575 1400);
WIRE 16 -1 (-2575 1400)(-1675 1400);
FORCEPROP 2 LAST SIG_NAME E1S_0_P3V3_P12V_ADC_R_ALERT
J 0
(-2535 1410);
DISPLAY 0.638298 (-2535 1410);
PAINT WHITE (-2535 1410);
WIRE 16 -1 (-2975 1400)(-2575 1400);
WIRE 16 -1 (-8375 750)(-8550 750);
WIRE 16 -1 (-8550 750)(-8550 275);
WIRE 16 -1 (-8550 750)(-8850 750);
WIRE 16 -1 (-8850 750)(-8850 850);
WIRE 16 -1 (-8550 275)(-6475 275);
WIRE 16 -1 (-8175 1425)(-8175 1550);
WIRE 16 -1 (-8175 1550)(-7925 1550);
WIRE 16 -1 (-7925 1600)(-7925 1550);
WIRE 16 -1 (-7925 1550)(-7925 1000);
WIRE 16 -1 (-5200 1000)(-7925 1000);
WIRE 16 -1 (-7075 5725)(-6750 5725);
WIRE 16 -1 (-7075 5775)(-7075 5725);
WIRE 16 -1 (-7075 5600)(-7075 5725);
WIRE 16 -1 (-6750 5775)(-7075 5775);
WIRE 16 -1 (-7775 750)(-7950 750);
WIRE 16 -1 (-7775 750)(-7775 850);
WIRE 16 -1 (-7950 750)(-8175 750);
WIRE 16 -1 (-7950 550)(-7950 750);
WIRE 16 -1 (-7950 550)(-6475 550);
WIRE 16 -1 (-7625 1425)(-7300 1425);
WIRE 16 -1 (-7625 1475)(-7625 1425);
WIRE 16 -1 (-7625 1275)(-7625 1425);
WIRE 16 -1 (-7300 1475)(-7625 1475);
WIRE 16 -1 (-4300 950)(-4175 950);
WIRE 16 -1 (-4175 950)(-4175 900);
WIRE 16 -1 (-4300 900)(-4175 900);
WIRE 16 -1 (-4175 900)(-4175 550);
WIRE 16 -1 (-5250 2100)(-5250 1975);
WIRE 16 -1 (-5500 1975)(-5250 1975);
WIRE 16 -1 (-5250 1975)(-5250 1400);
WIRE 16 -1 (-5250 1400)(-5200 1400);
WIRE 16 -1 (-5500 1850)(-5500 1975);
WIRE 16 -1 (-7175 3025)(-7350 3025);
WIRE 16 -1 (-7350 3025)(-7350 2550);
WIRE 16 -1 (-7350 3025)(-7650 3025);
WIRE 16 -1 (-7650 3025)(-7650 3125);
WIRE 16 -1 (-7350 2550)(-5275 2550);
WIRE 16 -1 (-6750 2825)(-5275 2825);
WIRE 16 -1 (-6750 2825)(-6750 3025);
WIRE 16 -1 (-6575 3025)(-6750 3025);
WIRE 16 -1 (-6750 3025)(-6975 3025);
WIRE 16 -1 (-6575 3025)(-6575 3125);
WIRE 16 -1 (-6100 3750)(-6425 3750);
WIRE 16 -1 (-6425 3750)(-6425 3675);
WIRE 16 -1 (-6425 3675)(-6100 3675);
WIRE 16 -1 (-6425 3550)(-6425 3675);
WIRE 16 -1 (-6975 3700)(-6975 3825);
WIRE 16 -1 (-6975 3825)(-6725 3825);
WIRE 16 -1 (-6725 3875)(-6725 3825);
WIRE 16 -1 (-6725 3825)(-6725 3275);
WIRE 16 -1 (-4000 3275)(-6725 3275);
WIRE 16 -1 (-4050 4375)(-4050 4250);
WIRE 16 -1 (-4050 4250)(-4050 3675);
WIRE 16 -1 (-4300 4250)(-4050 4250);
WIRE 16 -1 (-4300 4125)(-4300 4250);
WIRE 16 -1 (-4050 3675)(-4000 3675);
WIRE 16 -1 (-3100 3225)(-2975 3225);
WIRE 16 -1 (-2975 3225)(-2975 3175);
WIRE 16 -1 (-3100 3175)(-2975 3175);
WIRE 16 -1 (-2975 3175)(-2975 2825);
WIRE 16 -1 (-3750 5275)(-3625 5275);
WIRE 16 -1 (-3625 5275)(-3625 5225);
WIRE 16 -1 (-3750 5225)(-3625 5225);
WIRE 16 -1 (-3625 5225)(-3625 4875);
WIRE 16 -1 (-4700 6425)(-4700 6300);
WIRE 16 -1 (-4950 6300)(-4700 6300);
WIRE 16 -1 (-4700 6300)(-4700 5725);
WIRE 16 -1 (-4700 5725)(-4650 5725);
WIRE 16 -1 (-4950 6175)(-4950 6300);
WIRE 16 -1 (-3100 3425)(-2475 3425);
FORCEPROP 2 LAST SIG_NAME NC_INA230_7_NC3
J 0
(-2960 3435);
DISPLAY 0.638298 (-2960 3435);
PAINT SKYBLUE (-2960 3435);
FORCEPROP 2 LASTPROP $XRERR UNIQUE?
J 0
(-2445 3425);
DISPLAY 0.638298 (-2445 3425);
PAINT MONO (-2445 3425);
DISPLAY INVISIBLE (-2445 3425);
WIRE 16 -1 (-3100 3525)(-2475 3525);
FORCEPROP 2 LAST SIG_NAME NC_INA230_7_NC1
J 0
(-2960 3535);
DISPLAY 0.638298 (-2960 3535);
PAINT SKYBLUE (-2960 3535);
FORCEPROP 2 LASTPROP $XRERR UNIQUE?
J 0
(-2445 3525);
DISPLAY 0.638298 (-2445 3525);
PAINT MONO (-2445 3525);
DISPLAY INVISIBLE (-2445 3525);
WIRE 16 -1 (-3750 5575)(-3125 5575);
FORCEPROP 2 LAST SIG_NAME NC_INA230_6_NC1
J 0
(-3610 5585);
DISPLAY 0.638298 (-3610 5585);
FORCEPROP 2 LASTPROP $XRERR UNIQUE?
J 0
(-3095 5575);
DISPLAY 0.638298 (-3095 5575);
PAINT MONO (-3095 5575);
DISPLAY INVISIBLE (-3095 5575);
WIRE 16 -1 (-3750 5625)(-3125 5625);
FORCEPROP 2 LAST SIG_NAME NC_INA230_6_NC0
J 0
(-3610 5635);
DISPLAY 0.638298 (-3610 5635);
FORCEPROP 2 LASTPROP $XRERR UNIQUE?
J 0
(-3095 5625);
DISPLAY 0.638298 (-3095 5625);
PAINT MONO (-3095 5625);
DISPLAY INVISIBLE (-3095 5625);
WIRE 16 -1 (-4800 5725)(-4800 5575);
WIRE 16 -1 (-4800 5725)(-5475 5725);
FORCEPROP 2 LAST SIG_NAME INA230_6_A0
J 0
(-5360 5735);
DISPLAY 0.638298 (-5360 5735);
FORCEPROP 2 LASTPROP $XRERR UNIQUE?
J 0
(-5600 5735);
DISPLAY 0.638298 (-5600 5735);
PAINT MONO (-5600 5735);
DISPLAY INVISIBLE (-5600 5735);
WIRE 16 -1 (-4800 5575)(-4650 5575);
WIRE 16 -1 (-5475 5700)(-5475 5725);
WIRE 16 -1 (-5475 5725)(-6550 5725);
WIRE 16 -1 (-5350 1425)(-5350 1250);
WIRE 16 -1 (-5350 1425)(-7100 1425);
FORCEPROP 2 LAST SIG_NAME INA230_8_A0
J 0
(-5910 1435);
DISPLAY 0.638298 (-5910 1435);
PAINT WHITE (-5910 1435);
FORCEPROP 2 LASTPROP $XRERR UNIQUE?
J 0
(-6150 1435);
DISPLAY 0.638298 (-6150 1435);
PAINT MONO (-6150 1435);
DISPLAY INVISIBLE (-6150 1435);
WIRE 16 -1 (-5350 1250)(-5200 1250);
WIRE 16 -1 (-5300 1300)(-5200 1300);
WIRE 16 -1 (-5300 1475)(-5300 1300);
WIRE 16 -1 (-5300 1475)(-6025 1475);
FORCEPROP 2 LAST SIG_NAME INA230_8_A1
J 0
(-5910 1485);
DISPLAY 0.638298 (-5910 1485);
PAINT WHITE (-5910 1485);
FORCEPROP 2 LASTPROP $XRERR UNIQUE?
J 0
(-6150 1485);
DISPLAY 0.638298 (-6150 1485);
PAINT MONO (-6150 1485);
DISPLAY INVISIBLE (-6150 1485);
WIRE 16 -1 (-6025 1475)(-6100 1475);
WIRE 16 -1 (-6025 1400)(-6025 1475);
WIRE 16 -1 (-6100 1650)(-6100 1475);
WIRE 16 -1 (-7100 1475)(-6100 1475);
WIRE 16 -1 (-5100 3375)(-4000 3375);
FORCEPROP 2 LAST SIG_NAME SMB_INA230_7_3V3AUX_SDA_R1
J 0
(-4785 3385);
DISPLAY 0.553191 (-4785 3385);
PAINT SKYBLUE (-4785 3385);
FORCEPROP 2 LASTPROP $XRERR UNIQUE?
J 0
(-5025 3385);
DISPLAY 0.638298 (-5025 3385);
PAINT MONO (-5025 3385);
DISPLAY INVISIBLE (-5025 3385);
WIRE 16 -1 (-4825 3450)(-4825 3425);
WIRE 16 -1 (-4825 3425)(-4000 3425);
FORCEPROP 2 LAST SIG_NAME SMB_INA230_7_3V3AUX_SCL_R1
J 0
(-4785 3450);
DISPLAY 0.553191 (-4785 3450);
PAINT SKYBLUE (-4785 3450);
FORCEPROP 2 LASTPROP $XRERR UNIQUE?
J 0
(-5025 3450);
DISPLAY 0.638298 (-5025 3450);
PAINT MONO (-5025 3450);
DISPLAY INVISIBLE (-5025 3450);
WIRE 16 -1 (-5100 3425)(-4825 3425);
WIRE 16 -1 (-4150 3675)(-4150 3525);
WIRE 16 -1 (-4150 3675)(-4825 3675);
FORCEPROP 2 LAST SIG_NAME INA230_7_A0
J 0
(-4710 3685);
DISPLAY 0.638298 (-4710 3685);
PAINT SKYBLUE (-4710 3685);
FORCEPROP 2 LASTPROP $XRERR UNIQUE?
J 0
(-4950 3685);
DISPLAY 0.638298 (-4950 3685);
PAINT MONO (-4950 3685);
DISPLAY INVISIBLE (-4950 3685);
WIRE 16 -1 (-4150 3525)(-4000 3525);
WIRE 16 -1 (-4825 3650)(-4825 3675);
WIRE 16 -1 (-4825 3675)(-5900 3675);
WIRE 16 -1 (-4100 3575)(-4000 3575);
WIRE 16 -1 (-4100 3750)(-4100 3575);
WIRE 16 -1 (-4100 3750)(-4900 3750);
FORCEPROP 2 LAST SIG_NAME INA230_7_A1
J 0
(-4710 3760);
DISPLAY 0.638298 (-4710 3760);
PAINT SKYBLUE (-4710 3760);
FORCEPROP 2 LASTPROP $XRERR UNIQUE?
J 0
(-4950 3760);
DISPLAY 0.638298 (-4950 3760);
PAINT MONO (-4950 3760);
DISPLAY INVISIBLE (-4950 3760);
WIRE 16 -1 (-4900 3925)(-4900 3750);
WIRE 16 -1 (-5900 3750)(-4900 3750);
WIRE 16 -1 (-4875 4875)(-4875 5275);
WIRE 16 -1 (-4875 4875)(-5475 4875);
FORCEPROP 2 LAST SIG_NAME VSENSE_P12V_INA230_6_INP
J 0
(-5460 4885);
DISPLAY 0.510638 (-5460 4885);
FORCEPROP 2 LASTPROP $XRERR UNIQUE?
J 0
(-5700 4885);
DISPLAY 0.638298 (-5700 4885);
PAINT MONO (-5700 4885);
DISPLAY INVISIBLE (-5700 4885);
WIRE 16 -1 (-4875 5275)(-4650 5275);
WIRE 16 -1 (-5475 4825)(-5475 4875);
WIRE 16 -1 (-5475 4875)(-5725 4875);
WIRE 16 -1 (-4750 5775)(-4750 5625);
WIRE 16 -1 (-4750 5775)(-5550 5775);
FORCEPROP 2 LAST SIG_NAME INA230_6_A1
J 0
(-5360 5785);
DISPLAY 0.638298 (-5360 5785);
FORCEPROP 2 LASTPROP $XRERR UNIQUE?
J 0
(-5600 5785);
DISPLAY 0.638298 (-5600 5785);
PAINT MONO (-5600 5785);
DISPLAY INVISIBLE (-5600 5785);
WIRE 16 -1 (-4750 5625)(-4650 5625);
WIRE 16 -1 (-5550 5975)(-5550 5775);
WIRE 16 -1 (-6550 5775)(-5550 5775);
WIRE 16 -1 (-7550 1100)(-6500 1100);
FORCEPROP 2 LAST SIG_NAME SMB_INA230_8_3V3AUX_SDA_R
J 0
(-7485 1110);
DISPLAY 0.680851 (-7485 1110);
PAINT WHITE (-7485 1110);
WIRE 16 -1 (-6300 1150)(-5200 1150);
FORCEPROP 2 LAST SIG_NAME SMB_INA230_8_3V3AUX_SCL_R1
J 0
(-5985 1175);
DISPLAY 0.553191 (-5985 1175);
PAINT WHITE (-5985 1175);
FORCEPROP 2 LASTPROP $XRERR UNIQUE?
J 0
(-6225 1175);
DISPLAY 0.638298 (-6225 1175);
PAINT MONO (-6225 1175);
DISPLAY INVISIBLE (-6225 1175);
WIRE 16 -1 (-6025 1200)(-6025 1100);
WIRE 16 -1 (-6025 1100)(-5200 1100);
FORCEPROP 2 LAST SIG_NAME SMB_INA230_8_3V3AUX_SDA_R1
J 0
(-5985 1110);
DISPLAY 0.553191 (-5985 1110);
PAINT WHITE (-5985 1110);
FORCEPROP 2 LASTPROP $XRERR UNIQUE?
J 0
(-6225 1110);
DISPLAY 0.638298 (-6225 1110);
PAINT MONO (-6225 1110);
DISPLAY INVISIBLE (-6225 1110);
WIRE 16 -1 (-6300 1100)(-6025 1100);
WIRE 16 -1 (-5750 5475)(-4650 5475);
FORCEPROP 2 LAST SIG_NAME SMB_INA230_6_3V3AUX_SCL_R1
J 0
(-5435 5475);
DISPLAY 0.553191 (-5435 5475);
FORCEPROP 2 LASTPROP $XRERR UNIQUE?
J 0
(-5675 5475);
DISPLAY 0.638298 (-5675 5475);
PAINT MONO (-5675 5475);
DISPLAY INVISIBLE (-5675 5475);
WIRE 16 -1 (-5475 5500)(-5475 5425);
WIRE 16 -1 (-5475 5425)(-4650 5425);
FORCEPROP 2 LAST SIG_NAME SMB_INA230_6_3V3AUX_SDA_R1
J 0
(-5435 5435);
DISPLAY 0.553191 (-5435 5435);
FORCEPROP 2 LASTPROP $XRERR UNIQUE?
J 0
(-5675 5435);
DISPLAY 0.638298 (-5675 5435);
PAINT MONO (-5675 5435);
DISPLAY INVISIBLE (-5675 5435);
WIRE 16 -1 (-5750 5425)(-5475 5425);
WIRE 16 -1 (-6350 3375)(-5300 3375);
FORCEPROP 2 LAST SIG_NAME SMB_INA230_7_3V3AUX_SDA_R
J 0
(-6285 3385);
DISPLAY 0.680851 (-6285 3385);
PAINT SKYBLUE (-6285 3385);
WIRE 16 -1 (-7000 5425)(-5950 5425);
FORCEPROP 2 LAST SIG_NAME SMB_INA230_6_3V3AUX_SDA_R
J 0
(-6935 5435);
DISPLAY 0.680851 (-6935 5435);
WIRE 16 -1 (-7000 5475)(-5950 5475);
FORCEPROP 2 LAST SIG_NAME SMB_INA230_6_3V3AUX_SCL_R
J 0
(-6935 5485);
DISPLAY 0.680851 (-6935 5485);
WIRE 16 -1 (-4125 3175)(-4000 3175);
WIRE 16 -1 (-4125 2550)(-4125 3175);
WIRE 16 -1 (-4125 2550)(-4825 2550);
FORCEPROP 2 LAST SIG_NAME VSENSE_P12V_INA230_7_INN
J 0
(-4785 2560);
DISPLAY 0.510638 (-4785 2560);
PAINT SKYBLUE (-4785 2560);
FORCEPROP 2 LASTPROP $XRERR UNIQUE?
J 0
(-5025 2560);
DISPLAY 0.638298 (-5025 2560);
PAINT MONO (-5025 2560);
DISPLAY INVISIBLE (-5025 2560);
WIRE 16 -1 (-4825 2575)(-4825 2550);
WIRE 16 -1 (-5075 2550)(-4825 2550);
WIRE 16 -1 (-4775 5225)(-4650 5225);
WIRE 16 -1 (-4775 4600)(-4775 5225);
WIRE 16 -1 (-4775 4600)(-5475 4600);
FORCEPROP 2 LAST SIG_NAME VSENSE_P12V_INA230_6_INN
J 0
(-5435 4610);
DISPLAY 0.510638 (-5435 4610);
FORCEPROP 2 LASTPROP $XRERR UNIQUE?
J 0
(-5675 4610);
DISPLAY 0.638298 (-5675 4610);
PAINT MONO (-5675 4610);
DISPLAY INVISIBLE (-5675 4610);
WIRE 16 -1 (-5475 4625)(-5475 4600);
WIRE 16 -1 (-5725 4600)(-5475 4600);
WIRE 16 -1 (-3175 1400)(-4300 1400);
FORCEPROP 2 LAST SIG_NAME P12V_E1S_0_ADC_ALERT_R
J 0
(-4160 1410);
DISPLAY 0.638298 (-4160 1410);
PAINT WHITE (-4160 1410);
FORCEPROP 2 LASTPROP $XRERR UNIQUE?
J 0
(-4400 1410);
DISPLAY 0.638298 (-4400 1410);
PAINT MONO (-4400 1410);
DISPLAY INVISIBLE (-4400 1410);
WIRE 16 -1 (-1400 4000)(-1400 3675);
WIRE 16 -1 (-1400 3675)(-425 3675);
FORCEPROP 2 LAST SIG_NAME OCP_V3_2_P3V3_P12V_ADC_R_ALERT
J 0
(-1335 3685);
DISPLAY 0.638298 (-1335 3685);
PAINT SKYBLUE (-1335 3685);
WIRE 16 -1 (-1775 3675)(-1400 3675);
WIRE 16 -1 (-1975 3675)(-3100 3675);
FORCEPROP 2 LAST SIG_NAME P12V_OCP_V3_2_ADC_ALERT_R
J 0
(-2960 3685);
DISPLAY 0.638298 (-2960 3685);
PAINT SKYBLUE (-2960 3685);
FORCEPROP 2 LASTPROP $XRERR UNIQUE?
J 0
(-3200 3685);
DISPLAY 0.638298 (-3200 3685);
PAINT MONO (-3200 3685);
DISPLAY INVISIBLE (-3200 3685);
WIRE 16 -1 (-2425 5725)(-2025 5725);
WIRE 16 -1 (-2025 5725)(-1025 5725);
FORCEPROP 2 LAST SIG_NAME OCP_SFF_P3V3_P12V_ADC_R_ALERT
J 0
(-1960 5735);
DISPLAY 0.638298 (-1960 5735);
WIRE 16 -1 (-2025 6050)(-2025 5725);
WIRE 16 -1 (-4300 1150)(-3675 1150);
FORCEPROP 2 LAST SIG_NAME NC_INA230_8_NC3
J 0
(-4160 1160);
DISPLAY 0.638298 (-4160 1160);
PAINT WHITE (-4160 1160);
FORCEPROP 2 LASTPROP $XRERR UNIQUE?
J 0
(-3645 1150);
DISPLAY 0.638298 (-3645 1150);
PAINT MONO (-3645 1150);
DISPLAY INVISIBLE (-3645 1150);
WIRE 16 -1 (-4300 1200)(-3675 1200);
FORCEPROP 2 LAST SIG_NAME NC_INA230_8_NC2
J 0
(-4160 1210);
DISPLAY 0.638298 (-4160 1210);
PAINT WHITE (-4160 1210);
FORCEPROP 2 LASTPROP $XRERR UNIQUE?
J 0
(-3645 1200);
DISPLAY 0.638298 (-3645 1200);
PAINT MONO (-3645 1200);
DISPLAY INVISIBLE (-3645 1200);
WIRE 16 -1 (-4300 1100)(-3675 1100);
FORCEPROP 2 LAST SIG_NAME NC_INA230_8_NC4
J 0
(-4160 1110);
DISPLAY 0.638298 (-4160 1110);
PAINT WHITE (-4160 1110);
FORCEPROP 2 LASTPROP $XRERR UNIQUE?
J 0
(-3645 1100);
DISPLAY 0.638298 (-3645 1100);
PAINT MONO (-3645 1100);
DISPLAY INVISIBLE (-3645 1100);
WIRE 16 -1 (-4300 1300)(-3675 1300);
FORCEPROP 2 LAST SIG_NAME NC_INA230_8_NC0
J 0
(-4160 1310);
DISPLAY 0.638298 (-4160 1310);
PAINT WHITE (-4160 1310);
FORCEPROP 2 LASTPROP $XRERR UNIQUE?
J 0
(-3645 1300);
DISPLAY 0.638298 (-3645 1300);
PAINT MONO (-3645 1300);
DISPLAY INVISIBLE (-3645 1300);
WIRE 16 -1 (-3100 3475)(-2475 3475);
FORCEPROP 2 LAST SIG_NAME NC_INA230_7_NC2
J 0
(-2960 3485);
DISPLAY 0.638298 (-2960 3485);
PAINT SKYBLUE (-2960 3485);
FORCEPROP 2 LASTPROP $XRERR UNIQUE?
J 0
(-2445 3475);
DISPLAY 0.638298 (-2445 3475);
PAINT MONO (-2445 3475);
DISPLAY INVISIBLE (-2445 3475);
WIRE 16 -1 (-4300 1250)(-3675 1250);
FORCEPROP 2 LAST SIG_NAME NC_INA230_8_NC1
J 0
(-4160 1260);
DISPLAY 0.638298 (-4160 1260);
PAINT WHITE (-4160 1260);
FORCEPROP 2 LASTPROP $XRERR UNIQUE?
J 0
(-3645 1250);
DISPLAY 0.638298 (-3645 1250);
PAINT MONO (-3645 1250);
DISPLAY INVISIBLE (-3645 1250);
WIRE 16 -1 (-3750 5475)(-3125 5475);
FORCEPROP 2 LAST SIG_NAME NC_INA230_6_NC3
J 0
(-3610 5485);
DISPLAY 0.638298 (-3610 5485);
FORCEPROP 2 LASTPROP $XRERR UNIQUE?
J 0
(-3095 5475);
DISPLAY 0.638298 (-3095 5475);
PAINT MONO (-3095 5475);
DISPLAY INVISIBLE (-3095 5475);
WIRE 16 -1 (-3750 5525)(-3125 5525);
FORCEPROP 2 LAST SIG_NAME NC_INA230_6_NC2
J 0
(-3610 5535);
DISPLAY 0.638298 (-3610 5535);
FORCEPROP 2 LASTPROP $XRERR UNIQUE?
J 0
(-3095 5525);
DISPLAY 0.638298 (-3095 5525);
PAINT MONO (-3095 5525);
DISPLAY INVISIBLE (-3095 5525);
WIRE 16 -1 (-3750 5425)(-3125 5425);
FORCEPROP 2 LAST SIG_NAME NC_INA230_6_NC4
J 0
(-3610 5435);
DISPLAY 0.638298 (-3610 5435);
FORCEPROP 2 LASTPROP $XRERR UNIQUE?
J 0
(-3095 5425);
DISPLAY 0.638298 (-3095 5425);
PAINT MONO (-3095 5425);
DISPLAY INVISIBLE (-3095 5425);
WIRE 16 -1 (-3750 5375)(-3125 5375);
FORCEPROP 2 LAST SIG_NAME NC_INA230_6_NC5
J 0
(-3610 5385);
DISPLAY 0.638298 (-3610 5385);
FORCEPROP 2 LASTPROP $XRERR UNIQUE?
J 0
(-3095 5375);
DISPLAY 0.638298 (-3095 5375);
PAINT MONO (-3095 5375);
DISPLAY INVISIBLE (-3095 5375);
WIRE 16 -1 (-4300 1050)(-3675 1050);
FORCEPROP 2 LAST SIG_NAME NC_INA230_8_NC5
J 0
(-4160 1060);
DISPLAY 0.638298 (-4160 1060);
PAINT WHITE (-4160 1060);
FORCEPROP 2 LASTPROP $XRERR UNIQUE?
J 0
(-3645 1050);
DISPLAY 0.638298 (-3645 1050);
PAINT MONO (-3645 1050);
DISPLAY INVISIBLE (-3645 1050);
WIRE 16 -1 (-5325 900)(-5200 900);
WIRE 16 -1 (-5325 275)(-5325 900);
WIRE 16 -1 (-5325 275)(-6025 275);
FORCEPROP 2 LAST SIG_NAME VSENSE_P12V_INA230_8_INN
J 0
(-5985 285);
DISPLAY 0.510638 (-5985 285);
PAINT WHITE (-5985 285);
FORCEPROP 2 LASTPROP $XRERR UNIQUE?
J 0
(-6225 285);
DISPLAY 0.638298 (-6225 285);
PAINT MONO (-6225 285);
DISPLAY INVISIBLE (-6225 285);
WIRE 16 -1 (-6025 300)(-6025 275);
WIRE 16 -1 (-6275 275)(-6025 275);
WIRE 16 -1 (-5425 550)(-5425 950);
WIRE 16 -1 (-5425 550)(-6025 550);
FORCEPROP 2 LAST SIG_NAME VSENSE_P12V_INA230_8_INP
J 0
(-6010 560);
DISPLAY 0.510638 (-6010 560);
PAINT WHITE (-6010 560);
FORCEPROP 2 LASTPROP $XRERR UNIQUE?
J 0
(-6250 560);
DISPLAY 0.638298 (-6250 560);
PAINT MONO (-6250 560);
DISPLAY INVISIBLE (-6250 560);
WIRE 16 -1 (-5425 950)(-5200 950);
WIRE 16 -1 (-6025 500)(-6025 550);
WIRE 16 -1 (-6025 550)(-6275 550);
WIRE 16 -1 (-7550 1150)(-6500 1150);
FORCEPROP 2 LAST SIG_NAME SMB_INA230_8_3V3AUX_SCL_R
J 0
(-7485 1160);
DISPLAY 0.680851 (-7485 1160);
PAINT WHITE (-7485 1160);
WIRE 16 -1 (-3100 3575)(-2475 3575);
FORCEPROP 2 LAST SIG_NAME NC_INA230_7_NC0
J 0
(-2960 3585);
DISPLAY 0.638298 (-2960 3585);
PAINT SKYBLUE (-2960 3585);
FORCEPROP 2 LASTPROP $XRERR UNIQUE?
J 0
(-2445 3575);
DISPLAY 0.638298 (-2445 3575);
PAINT MONO (-2445 3575);
DISPLAY INVISIBLE (-2445 3575);
WIRE 16 -1 (-3100 3375)(-2475 3375);
FORCEPROP 2 LAST SIG_NAME NC_INA230_7_NC4
J 0
(-2960 3385);
DISPLAY 0.638298 (-2960 3385);
PAINT SKYBLUE (-2960 3385);
FORCEPROP 2 LASTPROP $XRERR UNIQUE?
J 0
(-2445 3375);
DISPLAY 0.638298 (-2445 3375);
PAINT MONO (-2445 3375);
DISPLAY INVISIBLE (-2445 3375);
WIRE 16 -1 (-4225 2825)(-4225 3225);
WIRE 16 -1 (-4225 2825)(-4825 2825);
FORCEPROP 2 LAST SIG_NAME VSENSE_P12V_INA230_7_INP
J 0
(-4810 2835);
DISPLAY 0.510638 (-4810 2835);
PAINT SKYBLUE (-4810 2835);
FORCEPROP 2 LASTPROP $XRERR UNIQUE?
J 0
(-5050 2835);
DISPLAY 0.638298 (-5050 2835);
PAINT MONO (-5050 2835);
DISPLAY INVISIBLE (-5050 2835);
WIRE 16 -1 (-4225 3225)(-4000 3225);
WIRE 16 -1 (-4825 2775)(-4825 2825);
WIRE 16 -1 (-4825 2825)(-5075 2825);
WIRE 16 -1 (-6350 3425)(-5300 3425);
FORCEPROP 2 LAST SIG_NAME SMB_INA230_7_3V3AUX_SCL_R
J 0
(-6285 3435);
DISPLAY 0.680851 (-6285 3435);
PAINT SKYBLUE (-6285 3435);
DOT 1 (-7375 5875);
DOT 1 (-4700 6300);
DOT 1 (-3625 5225);
DOT 1 (-6025 550);
DOT 1 (-6025 275);
DOT 1 (-7950 750);
DOT 1 (-8550 750);
DOT 1 (-7350 3025);
DOT 1 (-6750 3025);
DOT 1 (-6725 3825);
DOT 1 (-4825 2550);
DOT 1 (-4825 2825);
DOT 1 (-2975 3175);
DOT 1 (-4050 4250);
DOT 1 (-4175 900);
DOT 1 (-7925 1550);
DOT 1 (-5475 4875);
DOT 1 (-8000 5075);
DOT 1 (-7400 5075);
DOT 1 (-2025 5725);
DOT 1 (-1400 3675);
DOT 1 (-2575 1400);
DOT 1 (-7075 5725);
DOT 1 (-5550 5775);
DOT 1 (-5475 4600);
DOT 1 (-4900 3750);
DOT 1 (-6425 3675);
DOT 1 (-4825 3425);
DOT 1 (-5475 5725);
DOT 1 (-4825 3675);
DOT 1 (-7625 1425);
DOT 1 (-6025 1475);
DOT 1 (-6025 1100);
DOT 1 (-5250 1975);
DOT 1 (-6100 1475);
DOT 1 (-5475 5425);
FORCENOTE
ADDRESS : 0X8C (8-BIT)
(-3475 4925) 0;
DISPLAY LEFT (-3475 4925);
DISPLAY 1.340425 (-3475 4925);
PAINT WHITE (-3475 4925);
FORCENOTE
0X47 (7-BIT)
(-2200 2800) 0;
DISPLAY LEFT (-2200 2800);
DISPLAY 1.276596 (-2200 2800);
PAINT WHITE (-2200 2800);
FORCENOTE
ADDRESS : 0X90 (8-BIT)
(-4025 600) 0;
DISPLAY LEFT (-4025 600);
DISPLAY 1.340425 (-4025 600);
PAINT WHITE (-4025 600);
FORCENOTE
0X48 (7-BIT)
(-3400 525) 0;
DISPLAY LEFT (-3400 525);
DISPLAY 1.276596 (-3400 525);
PAINT WHITE (-3400 525);
FORCENOTE
ADDRESS : 0X8E (8-BIT)
(-2825 2875) 0;
DISPLAY LEFT (-2825 2875);
DISPLAY 1.340425 (-2825 2875);
PAINT WHITE (-2825 2875);
FORCENOTE
0X46 (7-BIT)
(-2850 4850) 0;
DISPLAY LEFT (-2850 4850);
DISPLAY 1.276596 (-2850 4850);
PAINT WHITE (-2850 4850);
QUIT
